FILE_TYPE = MACRO_DRAWING;
SET COLOR_WIRE YELLOW;
SET COLOR_PROP MONO;
SET COLOR_DOT WHITE;
SET COLOR_ARC YELLOW;
SET COLOR_BODY GREEN;
SET COLOR_NOTE MONO;
SET PROP_DISPLAY VALUE;
SET PAGE_NUMBER P52;
FORCEADD GND..1
R 2
(-3575 1500);
FORCEPROP 3 LASTPIN (-3575 1550) SIG_NAME GND\g
J 0
(-3565 1560);
DISPLAY 0.659574 (-3565 1560);
PAINT MONO (-3565 1560);
DISPLAY INVISIBLE (-3565 1560);
FORCEPROP 1 LAST VOLTAGE 0
J 0
(-3575 1500);
PAINT SKYBLUE (-3575 1500);
DISPLAY INVISIBLE (-3575 1500);
FORCEPROP 2 LAST CDS_LIB mstr_symbols
J 0
(-3575 1500);
DISPLAY 0.787234 (-3575 1500);
PAINT MONO (-3575 1500);
DISPLAY INVISIBLE (-3575 1500);
FORCEPROP 1 LAST SIZE 1B
J 2
(-3650 1450);
DISPLAY 1.170213 (-3650 1450);
PAINT GREEN (-3650 1450);
DISPLAY INVISIBLE (-3650 1450);
FORCEPROP 1 LAST BODY_TYPE PLUMBING
J 2
(-3530 1457);
DISPLAY 0.340426 (-3530 1457);
PAINT GREEN (-3530 1457);
DISPLAY INVISIBLE (-3530 1457);
FORCEPROP 1 LAST PATH I1
J 2
(-3650 1500);
DISPLAY 0.872340 (-3650 1500);
PAINT AQUA (-3650 1500);
DISPLAY INVISIBLE (-3650 1500);
FORCEPROP 1 LAST HDL_POWER GND
J 2
(-3575 1650);
DISPLAY 0.553191 (-3575 1650);
PAINT GREEN (-3575 1650);
DISPLAY INVISIBLE (-3575 1650);
FORCEADD OFFPAGE..6
(-2075 1500);
FORCEPROP 2 LAST $XR0 49 
J 0
(-2324 1500);
DISPLAY 0.638298 (-2324 1500);
PAINT MONO (-2324 1500);
FORCEPROP 2 LAST $XR1 50 
J 0
(-2414 1500);
DISPLAY 0.638298 (-2414 1500);
PAINT MONO (-2414 1500);
FORCEPROP 2 LAST $XR2 51 
J 0
(-2504 1500);
DISPLAY 0.638298 (-2504 1500);
PAINT MONO (-2504 1500);
FORCEPROP 2 LAST $XR3 53 
J 0
(-2594 1500);
DISPLAY 0.638298 (-2594 1500);
PAINT MONO (-2594 1500);
FORCEPROP 2 LAST $XR4 54 
J 0
(-2684 1500);
DISPLAY 0.638298 (-2684 1500);
PAINT MONO (-2684 1500);
FORCEPROP 2 LAST $XR5 99 
J 0
(-2774 1500);
DISPLAY 0.638298 (-2774 1500);
PAINT MONO (-2774 1500);
FORCEPROP 2 LASTPIN (-2025 1500) SIG_NAME SMB_DDR_DEF_VPP_SDA
J 0
(-1985 1510);
DISPLAY 0.617021 (-1985 1510);
PAINT ORANGE (-1985 1510);
FORCEPROP 2 LAST CDS_LIB mstr_standard
J 0
(-2075 1500);
DISPLAY 0.787234 (-2075 1500);
PAINT MONO (-2075 1500);
DISPLAY INVISIBLE (-2075 1500);
FORCEPROP 1 LAST OFFPAGE TRUE
J 0
(-1750 1375);
DISPLAY 0.936170 (-1750 1375);
PAINT GREEN (-1750 1375);
DISPLAY INVISIBLE (-1750 1375);
FORCEPROP 1 LAST COMMENT_BODY TRUE
J 0
(-1975 1425);
DISPLAY 0.936170 (-1975 1425);
PAINT GREEN (-1975 1425);
DISPLAY INVISIBLE (-1975 1425);
FORCEPROP 2 LAST PATH I10
J 0
(-2350 1550);
DISPLAY 1.021277 (-2350 1550);
PAINT ORANGE (-2350 1550);
DISPLAY INVISIBLE (-2350 1550);
FORCEADD SCONN288_H44441003..2
(1625 3900);
FORCEPROP 1 LAST LOCATION J6L2
J 0
(1225 5000);
DISPLAY 0.617021 (1225 5000);
PAINT AQUA (1225 5000);
FORCEPROP 1 LAST PART_NUMBER H44441-003
J 0
(1225 2800);
DISPLAY 0.617021 (1225 2800);
PAINT BLUE (1225 2800);
FORCEPROP 1 LAST MATERIAL SCONN
J 0
(1225 4950);
DISPLAY 0.617021 (1225 4950);
PAINT SKYBLUE (1225 4950);
FORCEPROP 2 LASTPIN (2075 4750) $PN 51
J 0
(2085 4760);
DISPLAY 0.617021 (2085 4760);
PAINT ORANGE (2085 4760);
FORCEPROP 2 LASTPIN (2075 4700) $PN 52
J 0
(2085 4710);
DISPLAY 0.617021 (2085 4710);
PAINT ORANGE (2085 4710);
FORCEPROP 2 LASTPIN (2075 4650) $PN 132
J 0
(2085 4660);
DISPLAY 0.617021 (2085 4660);
PAINT ORANGE (2085 4660);
FORCEPROP 2 LASTPIN (2075 4600) $PN 133
J 0
(2085 4610);
DISPLAY 0.617021 (2085 4610);
PAINT ORANGE (2085 4610);
FORCEPROP 2 LASTPIN (2075 4550) $PN 121
J 0
(2085 4560);
DISPLAY 0.617021 (2085 4560);
PAINT ORANGE (2085 4560);
FORCEPROP 2 LASTPIN (2075 4500) $PN 122
J 0
(2085 4510);
DISPLAY 0.617021 (2085 4510);
PAINT ORANGE (2085 4510);
FORCEPROP 2 LASTPIN (2075 4450) $PN 110
J 0
(2085 4460);
DISPLAY 0.617021 (2085 4460);
PAINT ORANGE (2085 4460);
FORCEPROP 2 LASTPIN (2075 4400) $PN 111
J 0
(2085 4410);
DISPLAY 0.617021 (2085 4410);
PAINT ORANGE (2085 4410);
FORCEPROP 2 LASTPIN (2075 4350) $PN 99
J 0
(2085 4360);
DISPLAY 0.617021 (2085 4360);
PAINT ORANGE (2085 4360);
FORCEPROP 2 LASTPIN (2075 4300) $PN 100
J 0
(2085 4310);
DISPLAY 0.617021 (2085 4310);
PAINT ORANGE (2085 4310);
FORCEPROP 2 LASTPIN (2075 4250) $PN 40
J 0
(2085 4260);
DISPLAY 0.617021 (2085 4260);
PAINT ORANGE (2085 4260);
FORCEPROP 2 LASTPIN (2075 4200) $PN 41
J 0
(2085 4210);
DISPLAY 0.617021 (2085 4210);
PAINT ORANGE (2085 4210);
FORCEPROP 2 LASTPIN (2075 4150) $PN 29
J 0
(2085 4160);
DISPLAY 0.617021 (2085 4160);
PAINT ORANGE (2085 4160);
FORCEPROP 2 LASTPIN (2075 4100) $PN 30
J 0
(2085 4110);
DISPLAY 0.617021 (2085 4110);
PAINT ORANGE (2085 4110);
FORCEPROP 2 LASTPIN (2075 4050) $PN 18
J 0
(2085 4060);
DISPLAY 0.617021 (2085 4060);
PAINT ORANGE (2085 4060);
FORCEPROP 2 LASTPIN (2075 4000) $PN 19
J 0
(2085 4010);
DISPLAY 0.617021 (2085 4010);
PAINT ORANGE (2085 4010);
FORCEPROP 2 LASTPIN (2075 3950) $PN 7
J 0
(2085 3960);
DISPLAY 0.617021 (2085 3960);
PAINT ORANGE (2085 3960);
FORCEPROP 2 LASTPIN (2075 3900) $PN 8
J 0
(2085 3910);
DISPLAY 0.617021 (2085 3910);
PAINT ORANGE (2085 3910);
FORCEPROP 2 LASTPIN (2075 3850) $PN 197
J 0
(2085 3860);
DISPLAY 0.617021 (2085 3860);
PAINT ORANGE (2085 3860);
FORCEPROP 2 LASTPIN (2075 3800) $PN 196
J 0
(2085 3810);
DISPLAY 0.617021 (2085 3810);
PAINT ORANGE (2085 3810);
FORCEPROP 2 LASTPIN (2075 3750) $PN 278
J 0
(2085 3760);
DISPLAY 0.617021 (2085 3760);
PAINT ORANGE (2085 3760);
FORCEPROP 2 LASTPIN (2075 3700) $PN 277
J 0
(2085 3710);
DISPLAY 0.617021 (2085 3710);
PAINT ORANGE (2085 3710);
FORCEPROP 2 LASTPIN (2075 3650) $PN 267
J 0
(2085 3660);
DISPLAY 0.617021 (2085 3660);
PAINT ORANGE (2085 3660);
FORCEPROP 2 LASTPIN (2075 3600) $PN 266
J 0
(2085 3610);
DISPLAY 0.617021 (2085 3610);
PAINT ORANGE (2085 3610);
FORCEPROP 2 LASTPIN (2075 3550) $PN 256
J 0
(2085 3560);
DISPLAY 0.617021 (2085 3560);
PAINT ORANGE (2085 3560);
FORCEPROP 2 LASTPIN (2075 3500) $PN 255
J 0
(2085 3510);
DISPLAY 0.617021 (2085 3510);
PAINT ORANGE (2085 3510);
FORCEPROP 2 LASTPIN (2075 3450) $PN 245
J 0
(2085 3460);
DISPLAY 0.617021 (2085 3460);
PAINT ORANGE (2085 3460);
FORCEPROP 2 LASTPIN (2075 3400) $PN 244
J 0
(2085 3410);
DISPLAY 0.617021 (2085 3410);
PAINT ORANGE (2085 3410);
FORCEPROP 2 LASTPIN (2075 3350) $PN 186
J 0
(2085 3360);
DISPLAY 0.617021 (2085 3360);
PAINT ORANGE (2085 3360);
FORCEPROP 2 LASTPIN (2075 3300) $PN 185
J 0
(2085 3310);
DISPLAY 0.617021 (2085 3310);
PAINT ORANGE (2085 3310);
FORCEPROP 2 LASTPIN (2075 3250) $PN 175
J 0
(2085 3260);
DISPLAY 0.617021 (2085 3260);
PAINT ORANGE (2085 3260);
FORCEPROP 2 LASTPIN (2075 3200) $PN 174
J 0
(2085 3210);
DISPLAY 0.617021 (2085 3210);
PAINT ORANGE (2085 3210);
FORCEPROP 2 LASTPIN (2075 3150) $PN 164
J 0
(2085 3160);
DISPLAY 0.617021 (2085 3160);
PAINT ORANGE (2085 3160);
FORCEPROP 2 LASTPIN (2075 3100) $PN 163
J 0
(2085 3110);
DISPLAY 0.617021 (2085 3110);
PAINT ORANGE (2085 3110);
FORCEPROP 2 LASTPIN (2075 3050) $PN 153
J 0
(2085 3060);
DISPLAY 0.617021 (2085 3060);
PAINT ORANGE (2085 3060);
FORCEPROP 2 LASTPIN (2075 3000) $PN 152
J 0
(2085 3010);
DISPLAY 0.617021 (2085 3010);
PAINT ORANGE (2085 3010);
FORCEPROP 1 LAST PACK_TYPE PIP
J 0
(1225 5050);
PAINT SKYBLUE (1225 5050);
DISPLAY INVISIBLE (1225 5050);
FORCEPROP 2 LAST BOM_COST MEM
J 0
(1225 5050);
PAINT MONO (1225 5050);
DISPLAY INVISIBLE (1225 5050);
FORCEPROP 2 LAST CDS_LIB mstr_sconn
J 0
(1625 3900);
PAINT ORANGE (1625 3900);
DISPLAY INVISIBLE (1625 3900);
FORCEPROP 2 LAST SEC_TYPE PIP
J 0
(1225 5050);
DISPLAY 1.021277 (1225 5050);
PAINT ORANGE (1225 5050);
DISPLAY INVISIBLE (1225 5050);
FORCEPROP 2 LAST SEC 2
J 0
(1225 5050);
DISPLAY 0.680851 (1225 5050);
PAINT MONO (1225 5050);
DISPLAY INVISIBLE (1225 5050);
FORCEPROP 2 LAST CDS_LOCATION J6L2
J 0
(1225 5000);
DISPLAY 0.617021 (1225 5000);
PAINT AQUA (1225 5000);
DISPLAY INVISIBLE (1225 5000);
FORCEPROP 1 LAST PATH I100
J 0
(1625 4950);
PAINT GREEN (1625 4950);
DISPLAY INVISIBLE (1625 4950);
FORCEPROP 2 LAST ROOM DDR4_CH_E
J 0
(1225 5050);
PAINT MONO (1225 5050);
DISPLAY INVISIBLE (1225 5050);
FORCEADD OFFPAGE..1
(-2275 4550);
FORCEPROP 2 LAST $XR0 27 
J 0
(-2496 4550);
DISPLAY 0.638298 (-2496 4550);
PAINT MONO (-2496 4550);
FORCEPROP 2 LAST $XR1 51 
J 0
(-2586 4550);
DISPLAY 0.638298 (-2586 4550);
PAINT MONO (-2586 4550);
FORCEPROP 2 LAST CDS_LIB mstr_standard
J 0
(-2275 4550);
DISPLAY 0.787234 (-2275 4550);
PAINT MONO (-2275 4550);
DISPLAY INVISIBLE (-2275 4550);
FORCEPROP 1 LAST OFFPAGE TRUE
J 0
(-1950 4425);
DISPLAY 0.936170 (-1950 4425);
PAINT GREEN (-1950 4425);
DISPLAY INVISIBLE (-1950 4425);
FORCEPROP 1 LAST COMMENT_BODY TRUE
J 0
(-2150 4450);
DISPLAY 0.936170 (-2150 4450);
PAINT GREEN (-2150 4450);
DISPLAY INVISIBLE (-2150 4450);
FORCEPROP 2 LAST PATH I101
J 0
(-2475 4600);
DISPLAY 1.021277 (-2475 4600);
PAINT ORANGE (-2475 4600);
DISPLAY INVISIBLE (-2475 4600);
FORCEADD TAP..6
(-1475 3750);
FORCEPROP 3 LASTPIN (-1425 3750) SIG_NAME M_E_MA<2>
J 0
(-1415 3760);
DISPLAY 0.659574 (-1415 3760);
PAINT MONO (-1415 3760);
DISPLAY INVISIBLE (-1415 3760);
FORCEPROP 1 LASTPIN (-1425 3750) BN 2
J 0
(-1475 3760);
DISPLAY 0.617021 (-1475 3760);
PAINT PINK (-1475 3760);
FORCEPROP 2 LAST CDS_LIB mstr_standard
J 2
(-1475 3750);
DISPLAY 0.787234 (-1475 3750);
PAINT MONO (-1475 3750);
DISPLAY INVISIBLE (-1475 3750);
FORCEPROP 1 LAST BODY_TYPE PLUMBING
J 0
(-1475 3700);
DISPLAY 1.234043 (-1475 3700);
PAINT GREEN (-1475 3700);
DISPLAY INVISIBLE (-1475 3700);
FORCEPROP 1 LAST HDL_TAP TRUE
J 0
(-1150 3625);
DISPLAY 1.234043 (-1150 3625);
PAINT GREEN (-1150 3625);
DISPLAY INVISIBLE (-1150 3625);
FORCEPROP 1 LAST PATH I102
J 0
(-1477 3750);
DISPLAY 0.872340 (-1477 3750);
PAINT GREEN (-1477 3750);
DISPLAY INVISIBLE (-1477 3750);
FORCEADD TAP..6
(-1475 3700);
FORCEPROP 3 LASTPIN (-1425 3700) SIG_NAME M_E_MA<1>
J 0
(-1415 3710);
DISPLAY 0.659574 (-1415 3710);
PAINT MONO (-1415 3710);
DISPLAY INVISIBLE (-1415 3710);
FORCEPROP 1 LASTPIN (-1425 3700) BN 1
J 0
(-1475 3710);
DISPLAY 0.617021 (-1475 3710);
PAINT PINK (-1475 3710);
FORCEPROP 2 LAST CDS_LIB mstr_standard
J 2
(-1475 3700);
DISPLAY 0.787234 (-1475 3700);
PAINT MONO (-1475 3700);
DISPLAY INVISIBLE (-1475 3700);
FORCEPROP 1 LAST BODY_TYPE PLUMBING
J 0
(-1475 3650);
DISPLAY 1.234043 (-1475 3650);
PAINT GREEN (-1475 3650);
DISPLAY INVISIBLE (-1475 3650);
FORCEPROP 1 LAST HDL_TAP TRUE
J 0
(-1150 3575);
DISPLAY 1.234043 (-1150 3575);
PAINT GREEN (-1150 3575);
DISPLAY INVISIBLE (-1150 3575);
FORCEPROP 1 LAST PATH I103
J 0
(-1477 3700);
DISPLAY 0.872340 (-1477 3700);
PAINT GREEN (-1477 3700);
DISPLAY INVISIBLE (-1477 3700);
FORCEADD TAP..6
(-1475 3800);
FORCEPROP 3 LASTPIN (-1425 3800) SIG_NAME M_E_MA<3>
J 0
(-1415 3810);
DISPLAY 0.659574 (-1415 3810);
PAINT MONO (-1415 3810);
DISPLAY INVISIBLE (-1415 3810);
FORCEPROP 1 LASTPIN (-1425 3800) BN 3
J 0
(-1475 3810);
DISPLAY 0.617021 (-1475 3810);
PAINT PINK (-1475 3810);
FORCEPROP 2 LAST CDS_LIB mstr_standard
J 2
(-1475 3800);
DISPLAY 0.787234 (-1475 3800);
PAINT MONO (-1475 3800);
DISPLAY INVISIBLE (-1475 3800);
FORCEPROP 1 LAST BODY_TYPE PLUMBING
J 0
(-1475 3750);
DISPLAY 1.234043 (-1475 3750);
PAINT GREEN (-1475 3750);
DISPLAY INVISIBLE (-1475 3750);
FORCEPROP 1 LAST HDL_TAP TRUE
J 0
(-1150 3675);
DISPLAY 1.234043 (-1150 3675);
PAINT GREEN (-1150 3675);
DISPLAY INVISIBLE (-1150 3675);
FORCEPROP 1 LAST PATH I104
J 0
(-1477 3800);
DISPLAY 0.872340 (-1477 3800);
PAINT GREEN (-1477 3800);
DISPLAY INVISIBLE (-1477 3800);
FORCEADD TAP..6
(-1475 3900);
FORCEPROP 3 LASTPIN (-1425 3900) SIG_NAME M_E_MA<5>
J 0
(-1415 3910);
DISPLAY 0.659574 (-1415 3910);
PAINT MONO (-1415 3910);
DISPLAY INVISIBLE (-1415 3910);
FORCEPROP 1 LASTPIN (-1425 3900) BN 5
J 0
(-1475 3910);
DISPLAY 0.617021 (-1475 3910);
PAINT PINK (-1475 3910);
FORCEPROP 2 LAST CDS_LIB mstr_standard
J 2
(-1475 3900);
DISPLAY 0.787234 (-1475 3900);
PAINT MONO (-1475 3900);
DISPLAY INVISIBLE (-1475 3900);
FORCEPROP 1 LAST BODY_TYPE PLUMBING
J 0
(-1475 3850);
DISPLAY 1.234043 (-1475 3850);
PAINT GREEN (-1475 3850);
DISPLAY INVISIBLE (-1475 3850);
FORCEPROP 1 LAST HDL_TAP TRUE
J 0
(-1150 3775);
DISPLAY 1.234043 (-1150 3775);
PAINT GREEN (-1150 3775);
DISPLAY INVISIBLE (-1150 3775);
FORCEPROP 1 LAST PATH I105
J 0
(-1477 3900);
DISPLAY 0.872340 (-1477 3900);
PAINT GREEN (-1477 3900);
DISPLAY INVISIBLE (-1477 3900);
FORCEADD TAP..6
(-1475 3850);
FORCEPROP 3 LASTPIN (-1425 3850) SIG_NAME M_E_MA<4>
J 0
(-1415 3860);
DISPLAY 0.659574 (-1415 3860);
PAINT MONO (-1415 3860);
DISPLAY INVISIBLE (-1415 3860);
FORCEPROP 1 LASTPIN (-1425 3850) BN 4
J 0
(-1475 3860);
DISPLAY 0.617021 (-1475 3860);
PAINT PINK (-1475 3860);
FORCEPROP 2 LAST CDS_LIB mstr_standard
J 2
(-1475 3850);
DISPLAY 0.787234 (-1475 3850);
PAINT MONO (-1475 3850);
DISPLAY INVISIBLE (-1475 3850);
FORCEPROP 1 LAST BODY_TYPE PLUMBING
J 0
(-1475 3800);
DISPLAY 1.234043 (-1475 3800);
PAINT GREEN (-1475 3800);
DISPLAY INVISIBLE (-1475 3800);
FORCEPROP 1 LAST HDL_TAP TRUE
J 0
(-1150 3725);
DISPLAY 1.234043 (-1150 3725);
PAINT GREEN (-1150 3725);
DISPLAY INVISIBLE (-1150 3725);
FORCEPROP 1 LAST PATH I106
J 0
(-1477 3850);
DISPLAY 0.872340 (-1477 3850);
PAINT GREEN (-1477 3850);
DISPLAY INVISIBLE (-1477 3850);
FORCEADD TAP..6
(-1475 3950);
FORCEPROP 3 LASTPIN (-1425 3950) SIG_NAME M_E_MA<6>
J 0
(-1415 3960);
DISPLAY 0.659574 (-1415 3960);
PAINT MONO (-1415 3960);
DISPLAY INVISIBLE (-1415 3960);
FORCEPROP 1 LASTPIN (-1425 3950) BN 6
J 0
(-1475 3960);
DISPLAY 0.617021 (-1475 3960);
PAINT PINK (-1475 3960);
FORCEPROP 2 LAST CDS_LIB mstr_standard
J 2
(-1475 3950);
DISPLAY 0.787234 (-1475 3950);
PAINT MONO (-1475 3950);
DISPLAY INVISIBLE (-1475 3950);
FORCEPROP 1 LAST BODY_TYPE PLUMBING
J 0
(-1475 3900);
DISPLAY 1.234043 (-1475 3900);
PAINT GREEN (-1475 3900);
DISPLAY INVISIBLE (-1475 3900);
FORCEPROP 1 LAST HDL_TAP TRUE
J 0
(-1150 3825);
DISPLAY 1.234043 (-1150 3825);
PAINT GREEN (-1150 3825);
DISPLAY INVISIBLE (-1150 3825);
FORCEPROP 1 LAST PATH I107
J 0
(-1477 3950);
DISPLAY 0.872340 (-1477 3950);
PAINT GREEN (-1477 3950);
DISPLAY INVISIBLE (-1477 3950);
FORCEADD TAP..6
(-1475 4050);
FORCEPROP 3 LASTPIN (-1425 4050) SIG_NAME M_E_MA<8>
J 0
(-1415 4060);
DISPLAY 0.659574 (-1415 4060);
PAINT MONO (-1415 4060);
DISPLAY INVISIBLE (-1415 4060);
FORCEPROP 1 LASTPIN (-1425 4050) BN 8
J 0
(-1475 4060);
DISPLAY 0.617021 (-1475 4060);
PAINT PINK (-1475 4060);
FORCEPROP 2 LAST CDS_LIB mstr_standard
J 2
(-1475 4050);
DISPLAY 0.787234 (-1475 4050);
PAINT MONO (-1475 4050);
DISPLAY INVISIBLE (-1475 4050);
FORCEPROP 1 LAST BODY_TYPE PLUMBING
J 0
(-1475 4000);
DISPLAY 1.234043 (-1475 4000);
PAINT GREEN (-1475 4000);
DISPLAY INVISIBLE (-1475 4000);
FORCEPROP 1 LAST HDL_TAP TRUE
J 0
(-1150 3925);
DISPLAY 1.234043 (-1150 3925);
PAINT GREEN (-1150 3925);
DISPLAY INVISIBLE (-1150 3925);
FORCEPROP 1 LAST PATH I108
J 0
(-1477 4050);
DISPLAY 0.872340 (-1477 4050);
PAINT GREEN (-1477 4050);
DISPLAY INVISIBLE (-1477 4050);
FORCEADD TAP..6
(-1475 4000);
FORCEPROP 3 LASTPIN (-1425 4000) SIG_NAME M_E_MA<7>
J 0
(-1415 4010);
DISPLAY 0.659574 (-1415 4010);
PAINT MONO (-1415 4010);
DISPLAY INVISIBLE (-1415 4010);
FORCEPROP 1 LASTPIN (-1425 4000) BN 7
J 0
(-1475 4010);
DISPLAY 0.617021 (-1475 4010);
PAINT PINK (-1475 4010);
FORCEPROP 2 LAST CDS_LIB mstr_standard
J 2
(-1475 4000);
DISPLAY 0.787234 (-1475 4000);
PAINT MONO (-1475 4000);
DISPLAY INVISIBLE (-1475 4000);
FORCEPROP 1 LAST BODY_TYPE PLUMBING
J 0
(-1475 3950);
DISPLAY 1.234043 (-1475 3950);
PAINT GREEN (-1475 3950);
DISPLAY INVISIBLE (-1475 3950);
FORCEPROP 1 LAST HDL_TAP TRUE
J 0
(-1150 3875);
DISPLAY 1.234043 (-1150 3875);
PAINT GREEN (-1150 3875);
DISPLAY INVISIBLE (-1150 3875);
FORCEPROP 1 LAST PATH I109
J 0
(-1477 4000);
DISPLAY 0.872340 (-1477 4000);
PAINT GREEN (-1477 4000);
DISPLAY INVISIBLE (-1477 4000);
FORCEADD OFFPAGE..1
(-2075 1450);
FORCEPROP 2 LAST $XR0 99 
J 0
(-2326 1450);
DISPLAY 0.638298 (-2326 1450);
PAINT MONO (-2326 1450);
FORCEPROP 2 LAST $XR1 49 
J 0
(-2416 1450);
DISPLAY 0.638298 (-2416 1450);
PAINT MONO (-2416 1450);
FORCEPROP 2 LAST $XR2 50 
J 0
(-2506 1450);
DISPLAY 0.638298 (-2506 1450);
PAINT MONO (-2506 1450);
FORCEPROP 2 LAST $XR3 51 
J 0
(-2596 1450);
DISPLAY 0.638298 (-2596 1450);
PAINT MONO (-2596 1450);
FORCEPROP 2 LAST $XR4 53 
J 0
(-2686 1450);
DISPLAY 0.638298 (-2686 1450);
PAINT MONO (-2686 1450);
FORCEPROP 2 LAST $XR5 54 
J 0
(-2776 1450);
DISPLAY 0.638298 (-2776 1450);
PAINT MONO (-2776 1450);
FORCEPROP 2 LAST CDS_LIB mstr_standard
J 0
(-2075 1450);
DISPLAY 0.787234 (-2075 1450);
PAINT MONO (-2075 1450);
DISPLAY INVISIBLE (-2075 1450);
FORCEPROP 1 LAST OFFPAGE TRUE
J 0
(-1750 1325);
DISPLAY 0.936170 (-1750 1325);
PAINT GREEN (-1750 1325);
DISPLAY INVISIBLE (-1750 1325);
FORCEPROP 1 LAST COMMENT_BODY TRUE
J 0
(-1950 1350);
DISPLAY 0.936170 (-1950 1350);
PAINT GREEN (-1950 1350);
DISPLAY INVISIBLE (-1950 1350);
FORCEPROP 2 LAST PATH I11
J 0
(-2350 1500);
DISPLAY 1.021277 (-2350 1500);
PAINT ORANGE (-2350 1500);
DISPLAY INVISIBLE (-2350 1500);
FORCEADD TAP..6
(-1475 4150);
FORCEPROP 3 LASTPIN (-1425 4150) SIG_NAME M_E_MA<10>
J 0
(-1415 4160);
DISPLAY 0.659574 (-1415 4160);
PAINT MONO (-1415 4160);
DISPLAY INVISIBLE (-1415 4160);
FORCEPROP 1 LASTPIN (-1425 4150) BN 10
J 0
(-1475 4160);
DISPLAY 0.617021 (-1475 4160);
PAINT PINK (-1475 4160);
FORCEPROP 2 LAST CDS_LIB mstr_standard
J 2
(-1475 4150);
DISPLAY 0.787234 (-1475 4150);
PAINT MONO (-1475 4150);
DISPLAY INVISIBLE (-1475 4150);
FORCEPROP 1 LAST BODY_TYPE PLUMBING
J 0
(-1475 4100);
DISPLAY 1.234043 (-1475 4100);
PAINT GREEN (-1475 4100);
DISPLAY INVISIBLE (-1475 4100);
FORCEPROP 1 LAST HDL_TAP TRUE
J 0
(-1150 4025);
DISPLAY 1.234043 (-1150 4025);
PAINT GREEN (-1150 4025);
DISPLAY INVISIBLE (-1150 4025);
FORCEPROP 1 LAST PATH I110
J 0
(-1477 4150);
DISPLAY 0.872340 (-1477 4150);
PAINT GREEN (-1477 4150);
DISPLAY INVISIBLE (-1477 4150);
FORCEADD TAP..6
(-1475 4100);
FORCEPROP 3 LASTPIN (-1425 4100) SIG_NAME M_E_MA<9>
J 0
(-1415 4110);
DISPLAY 0.659574 (-1415 4110);
PAINT MONO (-1415 4110);
DISPLAY INVISIBLE (-1415 4110);
FORCEPROP 1 LASTPIN (-1425 4100) BN 9
J 0
(-1475 4110);
DISPLAY 0.617021 (-1475 4110);
PAINT PINK (-1475 4110);
FORCEPROP 2 LAST CDS_LIB mstr_standard
J 2
(-1475 4100);
DISPLAY 0.787234 (-1475 4100);
PAINT MONO (-1475 4100);
DISPLAY INVISIBLE (-1475 4100);
FORCEPROP 1 LAST BODY_TYPE PLUMBING
J 0
(-1475 4050);
DISPLAY 1.234043 (-1475 4050);
PAINT GREEN (-1475 4050);
DISPLAY INVISIBLE (-1475 4050);
FORCEPROP 1 LAST HDL_TAP TRUE
J 0
(-1150 3975);
DISPLAY 1.234043 (-1150 3975);
PAINT GREEN (-1150 3975);
DISPLAY INVISIBLE (-1150 3975);
FORCEPROP 1 LAST PATH I111
J 0
(-1477 4100);
DISPLAY 0.872340 (-1477 4100);
PAINT GREEN (-1477 4100);
DISPLAY INVISIBLE (-1477 4100);
FORCEADD TAP..6
(-1475 4200);
FORCEPROP 3 LASTPIN (-1425 4200) SIG_NAME M_E_MA<11>
J 0
(-1415 4210);
DISPLAY 0.659574 (-1415 4210);
PAINT MONO (-1415 4210);
DISPLAY INVISIBLE (-1415 4210);
FORCEPROP 1 LASTPIN (-1425 4200) BN 11
J 0
(-1475 4210);
DISPLAY 0.617021 (-1475 4210);
PAINT PINK (-1475 4210);
FORCEPROP 2 LAST CDS_LIB mstr_standard
J 2
(-1475 4200);
DISPLAY 0.787234 (-1475 4200);
PAINT MONO (-1475 4200);
DISPLAY INVISIBLE (-1475 4200);
FORCEPROP 1 LAST BODY_TYPE PLUMBING
J 0
(-1475 4150);
DISPLAY 1.234043 (-1475 4150);
PAINT GREEN (-1475 4150);
DISPLAY INVISIBLE (-1475 4150);
FORCEPROP 1 LAST HDL_TAP TRUE
J 0
(-1150 4075);
DISPLAY 1.234043 (-1150 4075);
PAINT GREEN (-1150 4075);
DISPLAY INVISIBLE (-1150 4075);
FORCEPROP 1 LAST PATH I112
J 0
(-1477 4200);
DISPLAY 0.872340 (-1477 4200);
PAINT GREEN (-1477 4200);
DISPLAY INVISIBLE (-1477 4200);
FORCEADD TAP..6
(-1475 4300);
FORCEPROP 3 LASTPIN (-1425 4300) SIG_NAME M_E_MA<13>
J 0
(-1415 4310);
DISPLAY 0.659574 (-1415 4310);
PAINT MONO (-1415 4310);
DISPLAY INVISIBLE (-1415 4310);
FORCEPROP 1 LASTPIN (-1425 4300) BN 13
J 0
(-1475 4310);
DISPLAY 0.617021 (-1475 4310);
PAINT PINK (-1475 4310);
FORCEPROP 2 LAST CDS_LIB mstr_standard
J 2
(-1475 4300);
DISPLAY 0.787234 (-1475 4300);
PAINT MONO (-1475 4300);
DISPLAY INVISIBLE (-1475 4300);
FORCEPROP 1 LAST BODY_TYPE PLUMBING
J 0
(-1475 4250);
DISPLAY 1.234043 (-1475 4250);
PAINT GREEN (-1475 4250);
DISPLAY INVISIBLE (-1475 4250);
FORCEPROP 1 LAST HDL_TAP TRUE
J 0
(-1150 4175);
DISPLAY 1.234043 (-1150 4175);
PAINT GREEN (-1150 4175);
DISPLAY INVISIBLE (-1150 4175);
FORCEPROP 1 LAST PATH I113
J 0
(-1477 4300);
DISPLAY 0.872340 (-1477 4300);
PAINT GREEN (-1477 4300);
DISPLAY INVISIBLE (-1477 4300);
FORCEADD TAP..6
(-1475 4250);
FORCEPROP 3 LASTPIN (-1425 4250) SIG_NAME M_E_MA<12>
J 0
(-1415 4260);
DISPLAY 0.659574 (-1415 4260);
PAINT MONO (-1415 4260);
DISPLAY INVISIBLE (-1415 4260);
FORCEPROP 1 LASTPIN (-1425 4250) BN 12
J 0
(-1475 4260);
DISPLAY 0.617021 (-1475 4260);
PAINT PINK (-1475 4260);
FORCEPROP 2 LAST CDS_LIB mstr_standard
J 2
(-1475 4250);
DISPLAY 0.787234 (-1475 4250);
PAINT MONO (-1475 4250);
DISPLAY INVISIBLE (-1475 4250);
FORCEPROP 1 LAST BODY_TYPE PLUMBING
J 0
(-1475 4200);
DISPLAY 1.234043 (-1475 4200);
PAINT GREEN (-1475 4200);
DISPLAY INVISIBLE (-1475 4200);
FORCEPROP 1 LAST HDL_TAP TRUE
J 0
(-1150 4125);
DISPLAY 1.234043 (-1150 4125);
PAINT GREEN (-1150 4125);
DISPLAY INVISIBLE (-1150 4125);
FORCEPROP 1 LAST PATH I114
J 0
(-1477 4250);
DISPLAY 0.872340 (-1477 4250);
PAINT GREEN (-1477 4250);
DISPLAY INVISIBLE (-1477 4250);
FORCEADD TAP..6
(-1475 4400);
FORCEPROP 3 LASTPIN (-1425 4400) SIG_NAME M_E_MA<15>
J 0
(-1415 4410);
DISPLAY 0.659574 (-1415 4410);
PAINT MONO (-1415 4410);
DISPLAY INVISIBLE (-1415 4410);
FORCEPROP 1 LASTPIN (-1425 4400) BN 15
J 0
(-1475 4410);
DISPLAY 0.617021 (-1475 4410);
PAINT PINK (-1475 4410);
FORCEPROP 2 LAST CDS_LIB mstr_standard
J 2
(-1475 4400);
DISPLAY 0.787234 (-1475 4400);
PAINT MONO (-1475 4400);
DISPLAY INVISIBLE (-1475 4400);
FORCEPROP 1 LAST BODY_TYPE PLUMBING
J 0
(-1475 4350);
DISPLAY 1.234043 (-1475 4350);
PAINT GREEN (-1475 4350);
DISPLAY INVISIBLE (-1475 4350);
FORCEPROP 1 LAST HDL_TAP TRUE
J 0
(-1150 4275);
DISPLAY 1.234043 (-1150 4275);
PAINT GREEN (-1150 4275);
DISPLAY INVISIBLE (-1150 4275);
FORCEPROP 1 LAST PATH I115
J 0
(-1477 4400);
DISPLAY 0.872340 (-1477 4400);
PAINT GREEN (-1477 4400);
DISPLAY INVISIBLE (-1477 4400);
FORCEADD TAP..6
(-1475 4350);
FORCEPROP 3 LASTPIN (-1425 4350) SIG_NAME M_E_MA<14>
J 0
(-1415 4360);
DISPLAY 0.659574 (-1415 4360);
PAINT MONO (-1415 4360);
DISPLAY INVISIBLE (-1415 4360);
FORCEPROP 1 LASTPIN (-1425 4350) BN 14
J 0
(-1475 4360);
DISPLAY 0.617021 (-1475 4360);
PAINT PINK (-1475 4360);
FORCEPROP 2 LAST CDS_LIB mstr_standard
J 2
(-1475 4350);
DISPLAY 0.787234 (-1475 4350);
PAINT MONO (-1475 4350);
DISPLAY INVISIBLE (-1475 4350);
FORCEPROP 1 LAST BODY_TYPE PLUMBING
J 0
(-1475 4300);
DISPLAY 1.234043 (-1475 4300);
PAINT GREEN (-1475 4300);
DISPLAY INVISIBLE (-1475 4300);
FORCEPROP 1 LAST HDL_TAP TRUE
J 0
(-1150 4225);
DISPLAY 1.234043 (-1150 4225);
PAINT GREEN (-1150 4225);
DISPLAY INVISIBLE (-1150 4225);
FORCEPROP 1 LAST PATH I116
J 0
(-1477 4350);
DISPLAY 0.872340 (-1477 4350);
PAINT GREEN (-1477 4350);
DISPLAY INVISIBLE (-1477 4350);
FORCEADD TAP..6
(-1475 4450);
FORCEPROP 3 LASTPIN (-1425 4450) SIG_NAME M_E_MA<16>
J 0
(-1415 4460);
DISPLAY 0.659574 (-1415 4460);
PAINT MONO (-1415 4460);
DISPLAY INVISIBLE (-1415 4460);
FORCEPROP 1 LASTPIN (-1425 4450) BN 16
J 0
(-1475 4460);
DISPLAY 0.617021 (-1475 4460);
PAINT PINK (-1475 4460);
FORCEPROP 2 LAST CDS_LIB mstr_standard
J 2
(-1475 4450);
DISPLAY 0.787234 (-1475 4450);
PAINT MONO (-1475 4450);
DISPLAY INVISIBLE (-1475 4450);
FORCEPROP 1 LAST BODY_TYPE PLUMBING
J 0
(-1475 4400);
DISPLAY 1.234043 (-1475 4400);
PAINT GREEN (-1475 4400);
DISPLAY INVISIBLE (-1475 4400);
FORCEPROP 1 LAST HDL_TAP TRUE
J 0
(-1150 4325);
DISPLAY 1.234043 (-1150 4325);
PAINT GREEN (-1150 4325);
DISPLAY INVISIBLE (-1150 4325);
FORCEPROP 1 LAST PATH I117
J 0
(-1477 4450);
DISPLAY 0.872340 (-1477 4450);
PAINT GREEN (-1477 4450);
DISPLAY INVISIBLE (-1477 4450);
FORCEADD TAP..6
(-1475 4500);
FORCEPROP 3 LASTPIN (-1425 4500) SIG_NAME M_E_MA<17>
J 0
(-1415 4510);
DISPLAY 0.659574 (-1415 4510);
PAINT MONO (-1415 4510);
DISPLAY INVISIBLE (-1415 4510);
FORCEPROP 1 LASTPIN (-1425 4500) BN 17
J 0
(-1475 4510);
DISPLAY 0.617021 (-1475 4510);
PAINT PINK (-1475 4510);
FORCEPROP 2 LAST CDS_LIB mstr_standard
J 0
(-1475 4500);
DISPLAY 0.787234 (-1475 4500);
PAINT MONO (-1475 4500);
DISPLAY INVISIBLE (-1475 4500);
FORCEPROP 1 LAST BODY_TYPE PLUMBING
J 0
(-1475 4450);
DISPLAY 1.234043 (-1475 4450);
PAINT GREEN (-1475 4450);
DISPLAY INVISIBLE (-1475 4450);
FORCEPROP 1 LAST HDL_TAP TRUE
J 0
(-1150 4375);
DISPLAY 1.234043 (-1150 4375);
PAINT GREEN (-1150 4375);
DISPLAY INVISIBLE (-1150 4375);
FORCEPROP 1 LAST PATH I118
J 0
(-1477 4500);
DISPLAY 0.872340 (-1477 4500);
PAINT GREEN (-1477 4500);
DISPLAY INVISIBLE (-1477 4500);
FORCEADD TAP..6
R 2
(25 3800);
FORCEPROP 3 LASTPIN (-25 3800) SIG_NAME M_E_DQ<49>
J 0
(-15 3810);
DISPLAY 0.659574 (-15 3810);
PAINT MONO (-15 3810);
DISPLAY INVISIBLE (-15 3810);
FORCEPROP 1 LASTPIN (-25 3800) BN 49
J 2
(25 3810);
DISPLAY 0.617021 (25 3810);
PAINT PINK (25 3810);
FORCEPROP 2 LAST CDS_LIB mstr_standard
J 2
(25 3800);
DISPLAY 0.787234 (25 3800);
PAINT MONO (25 3800);
DISPLAY INVISIBLE (25 3800);
FORCEPROP 1 LAST BODY_TYPE PLUMBING
J 2
(25 3750);
DISPLAY 1.234043 (25 3750);
PAINT GREEN (25 3750);
DISPLAY INVISIBLE (25 3750);
FORCEPROP 1 LAST HDL_TAP TRUE
J 2
(-300 3675);
DISPLAY 1.234043 (-300 3675);
PAINT GREEN (-300 3675);
DISPLAY INVISIBLE (-300 3675);
FORCEPROP 1 LAST PATH I119
J 2
(27 3800);
DISPLAY 0.872340 (27 3800);
PAINT GREEN (27 3800);
DISPLAY INVISIBLE (27 3800);
FORCEADD SCONN288_H44441003..1
(-725 2850);
FORCEPROP 1 LAST LOCATION J6L2
J 0
(-1175 4750);
DISPLAY 0.617021 (-1175 4750);
PAINT AQUA (-1175 4750);
FORCEPROP 1 LAST PART_NUMBER H44441-003
J 0
(-1175 850);
DISPLAY 0.617021 (-1175 850);
PAINT BLUE (-1175 850);
FORCEPROP 1 LAST MATERIAL SCONN
J 0
(-1175 4700);
DISPLAY 0.617021 (-1175 4700);
PAINT SKYBLUE (-1175 4700);
FORCEPROP 2 LASTPIN (-1225 1350) $PN 146
J 2
(-1235 1360);
DISPLAY 0.617021 (-1235 1360);
PAINT ORANGE (-1235 1360);
FORCEPROP 2 LASTPIN (-1225 1700) $PN 284
J 2
(-1235 1710);
DISPLAY 0.617021 (-1235 1710);
PAINT ORANGE (-1235 1710);
FORCEPROP 2 LASTPIN (-1225 1500) $PN 285
J 2
(-1235 1510);
DISPLAY 0.617021 (-1235 1510);
PAINT ORANGE (-1235 1510);
FORCEPROP 2 LASTPIN (-1225 1450) $PN 141
J 2
(-1235 1460);
DISPLAY 0.617021 (-1235 1460);
PAINT ORANGE (-1235 1460);
FORCEPROP 2 LASTPIN (-1225 1050) $PN 230
J 2
(-1235 1060);
DISPLAY 0.617021 (-1235 1060);
PAINT ORANGE (-1235 1060);
FORCEPROP 2 LASTPIN (-1225 1650) $PN 238
J 2
(-1235 1660);
DISPLAY 0.617021 (-1235 1660);
PAINT ORANGE (-1235 1660);
FORCEPROP 2 LASTPIN (-1225 1600) $PN 140
J 2
(-1235 1610);
DISPLAY 0.617021 (-1235 1610);
PAINT ORANGE (-1235 1610);
FORCEPROP 2 LASTPIN (-1225 1550) $PN 139
J 2
(-1235 1560);
DISPLAY 0.617021 (-1235 1560);
PAINT ORANGE (-1235 1560);
FORCEPROP 2 LASTPIN (-1225 3000) $PN 237
J 2
(-1235 3010);
DISPLAY 0.617021 (-1235 3010);
PAINT ORANGE (-1235 3010);
FORCEPROP 2 LASTPIN (-1225 2950) $PN 93
J 2
(-1235 2960);
DISPLAY 0.617021 (-1235 2960);
PAINT ORANGE (-1235 2960);
FORCEPROP 2 LASTPIN (-1225 2900) $PN 89
J 2
(-1235 2910);
DISPLAY 0.617021 (-1235 2910);
PAINT ORANGE (-1235 2910);
FORCEPROP 2 LASTPIN (-1225 2850) $PN 84
J 2
(-1235 2860);
DISPLAY 0.617021 (-1235 2860);
PAINT ORANGE (-1235 2860);
FORCEPROP 2 LASTPIN (-1225 1250) $PN 144
J 2
(-1235 1260);
DISPLAY 0.617021 (-1235 1260);
PAINT ORANGE (-1235 1260);
FORCEPROP 2 LASTPIN (-1225 1200) $PN 227
J 2
(-1235 1210);
DISPLAY 0.617021 (-1235 1210);
PAINT ORANGE (-1235 1210);
FORCEPROP 2 LASTPIN (-1225 1150) $PN 205
J 2
(-1235 1160);
DISPLAY 0.617021 (-1235 1160);
PAINT ORANGE (-1235 1160);
FORCEPROP 2 LASTPIN (-1225 1950) $PN 58
J 2
(-1235 1960);
DISPLAY 0.617021 (-1235 1960);
PAINT ORANGE (-1235 1960);
FORCEPROP 2 LASTPIN (-1225 2000) $PN 222
J 2
(-1235 2010);
DISPLAY 0.617021 (-1235 2010);
PAINT ORANGE (-1235 2010);
FORCEPROP 2 LASTPIN (-1225 2600) $PN 91
J 2
(-1235 2610);
DISPLAY 0.617021 (-1235 2610);
PAINT ORANGE (-1235 2610);
FORCEPROP 2 LASTPIN (-1225 2550) $PN 87
J 2
(-1235 2560);
DISPLAY 0.617021 (-1235 2560);
PAINT ORANGE (-1235 2560);
FORCEPROP 2 LASTPIN (-1225 1900) $PN 78
J 2
(-1235 1910);
DISPLAY 0.617021 (-1235 1910);
PAINT ORANGE (-1235 1910);
FORCEPROP 2 LASTPIN (-225 4500) $PN 280
J 0
(-215 4510);
DISPLAY 0.617021 (-215 4510);
PAINT ORANGE (-215 4510);
FORCEPROP 2 LASTPIN (-225 4450) $PN 135
J 0
(-215 4460);
DISPLAY 0.617021 (-215 4460);
PAINT ORANGE (-215 4460);
FORCEPROP 2 LASTPIN (-225 4400) $PN 273
J 0
(-215 4410);
DISPLAY 0.617021 (-215 4410);
PAINT ORANGE (-215 4410);
FORCEPROP 2 LASTPIN (-225 4350) $PN 128
J 0
(-215 4360);
DISPLAY 0.617021 (-215 4360);
PAINT ORANGE (-215 4360);
FORCEPROP 2 LASTPIN (-225 4300) $PN 282
J 0
(-215 4310);
DISPLAY 0.617021 (-215 4310);
PAINT ORANGE (-215 4310);
FORCEPROP 2 LASTPIN (-225 4250) $PN 137
J 0
(-215 4260);
DISPLAY 0.617021 (-215 4260);
PAINT ORANGE (-215 4260);
FORCEPROP 2 LASTPIN (-225 4200) $PN 275
J 0
(-215 4210);
DISPLAY 0.617021 (-215 4210);
PAINT ORANGE (-215 4210);
FORCEPROP 2 LASTPIN (-225 4150) $PN 130
J 0
(-215 4160);
DISPLAY 0.617021 (-215 4160);
PAINT ORANGE (-215 4160);
FORCEPROP 2 LASTPIN (-225 4100) $PN 269
J 0
(-215 4110);
DISPLAY 0.617021 (-215 4110);
PAINT ORANGE (-215 4110);
FORCEPROP 2 LASTPIN (-225 4050) $PN 124
J 0
(-215 4060);
DISPLAY 0.617021 (-215 4060);
PAINT ORANGE (-215 4060);
FORCEPROP 2 LASTPIN (-225 4000) $PN 262
J 0
(-215 4010);
DISPLAY 0.617021 (-215 4010);
PAINT ORANGE (-215 4010);
FORCEPROP 2 LASTPIN (-225 3950) $PN 117
J 0
(-215 3960);
DISPLAY 0.617021 (-215 3960);
PAINT ORANGE (-215 3960);
FORCEPROP 2 LASTPIN (-225 3900) $PN 271
J 0
(-215 3910);
DISPLAY 0.617021 (-215 3910);
PAINT ORANGE (-215 3910);
FORCEPROP 2 LASTPIN (-225 3850) $PN 126
J 0
(-215 3860);
DISPLAY 0.617021 (-215 3860);
PAINT ORANGE (-215 3860);
FORCEPROP 2 LASTPIN (-225 3800) $PN 264
J 0
(-215 3810);
DISPLAY 0.617021 (-215 3810);
PAINT ORANGE (-215 3810);
FORCEPROP 2 LASTPIN (-225 3750) $PN 119
J 0
(-215 3760);
DISPLAY 0.617021 (-215 3760);
PAINT ORANGE (-215 3760);
FORCEPROP 2 LASTPIN (-225 3700) $PN 258
J 0
(-215 3710);
DISPLAY 0.617021 (-215 3710);
PAINT ORANGE (-215 3710);
FORCEPROP 2 LASTPIN (-225 3650) $PN 113
J 0
(-215 3660);
DISPLAY 0.617021 (-215 3660);
PAINT ORANGE (-215 3660);
FORCEPROP 2 LASTPIN (-225 3600) $PN 251
J 0
(-215 3610);
DISPLAY 0.617021 (-215 3610);
PAINT ORANGE (-215 3610);
FORCEPROP 2 LASTPIN (-225 3550) $PN 106
J 0
(-215 3560);
DISPLAY 0.617021 (-215 3560);
PAINT ORANGE (-215 3560);
FORCEPROP 2 LASTPIN (-225 3500) $PN 260
J 0
(-215 3510);
DISPLAY 0.617021 (-215 3510);
PAINT ORANGE (-215 3510);
FORCEPROP 2 LASTPIN (-225 3450) $PN 115
J 0
(-215 3460);
DISPLAY 0.617021 (-215 3460);
PAINT ORANGE (-215 3460);
FORCEPROP 2 LASTPIN (-225 3400) $PN 253
J 0
(-215 3410);
DISPLAY 0.617021 (-215 3410);
PAINT ORANGE (-215 3410);
FORCEPROP 2 LASTPIN (-225 3350) $PN 108
J 0
(-215 3360);
DISPLAY 0.617021 (-215 3360);
PAINT ORANGE (-215 3360);
FORCEPROP 2 LASTPIN (-225 3300) $PN 247
J 0
(-215 3310);
DISPLAY 0.617021 (-215 3310);
PAINT ORANGE (-215 3310);
FORCEPROP 2 LASTPIN (-225 3250) $PN 102
J 0
(-215 3260);
DISPLAY 0.617021 (-215 3260);
PAINT ORANGE (-215 3260);
FORCEPROP 2 LASTPIN (-225 3200) $PN 240
J 0
(-215 3210);
DISPLAY 0.617021 (-215 3210);
PAINT ORANGE (-215 3210);
FORCEPROP 2 LASTPIN (-225 3150) $PN 95
J 0
(-215 3160);
DISPLAY 0.617021 (-215 3160);
PAINT ORANGE (-215 3160);
FORCEPROP 2 LASTPIN (-225 3100) $PN 249
J 0
(-215 3110);
DISPLAY 0.617021 (-215 3110);
PAINT ORANGE (-215 3110);
FORCEPROP 2 LASTPIN (-225 3050) $PN 104
J 0
(-215 3060);
DISPLAY 0.617021 (-215 3060);
PAINT ORANGE (-215 3060);
FORCEPROP 2 LASTPIN (-225 3000) $PN 242
J 0
(-215 3010);
DISPLAY 0.617021 (-215 3010);
PAINT ORANGE (-215 3010);
FORCEPROP 2 LASTPIN (-225 2950) $PN 97
J 0
(-215 2960);
DISPLAY 0.617021 (-215 2960);
PAINT ORANGE (-215 2960);
FORCEPROP 2 LASTPIN (-225 2900) $PN 188
J 0
(-215 2910);
DISPLAY 0.617021 (-215 2910);
PAINT ORANGE (-215 2910);
FORCEPROP 2 LASTPIN (-225 2850) $PN 43
J 0
(-215 2860);
DISPLAY 0.617021 (-215 2860);
PAINT ORANGE (-215 2860);
FORCEPROP 2 LASTPIN (-225 2800) $PN 181
J 0
(-215 2810);
DISPLAY 0.617021 (-215 2810);
PAINT ORANGE (-215 2810);
FORCEPROP 2 LASTPIN (-225 2750) $PN 36
J 0
(-215 2760);
DISPLAY 0.617021 (-215 2760);
PAINT ORANGE (-215 2760);
FORCEPROP 2 LASTPIN (-225 2700) $PN 190
J 0
(-215 2710);
DISPLAY 0.617021 (-215 2710);
PAINT ORANGE (-215 2710);
FORCEPROP 2 LASTPIN (-225 2650) $PN 45
J 0
(-215 2660);
DISPLAY 0.617021 (-215 2660);
PAINT ORANGE (-215 2660);
FORCEPROP 2 LASTPIN (-225 2600) $PN 183
J 0
(-215 2610);
DISPLAY 0.617021 (-215 2610);
PAINT ORANGE (-215 2610);
FORCEPROP 2 LASTPIN (-225 2550) $PN 38
J 0
(-215 2560);
DISPLAY 0.617021 (-215 2560);
PAINT ORANGE (-215 2560);
FORCEPROP 2 LASTPIN (-225 2500) $PN 177
J 0
(-215 2510);
DISPLAY 0.617021 (-215 2510);
PAINT ORANGE (-215 2510);
FORCEPROP 2 LASTPIN (-225 2450) $PN 32
J 0
(-215 2460);
DISPLAY 0.617021 (-215 2460);
PAINT ORANGE (-215 2460);
FORCEPROP 2 LASTPIN (-225 2400) $PN 170
J 0
(-215 2410);
DISPLAY 0.617021 (-215 2410);
PAINT ORANGE (-215 2410);
FORCEPROP 2 LASTPIN (-225 2350) $PN 25
J 0
(-215 2360);
DISPLAY 0.617021 (-215 2360);
PAINT ORANGE (-215 2360);
FORCEPROP 2 LASTPIN (-225 2300) $PN 179
J 0
(-215 2310);
DISPLAY 0.617021 (-215 2310);
PAINT ORANGE (-215 2310);
FORCEPROP 2 LASTPIN (-225 2250) $PN 34
J 0
(-215 2260);
DISPLAY 0.617021 (-215 2260);
PAINT ORANGE (-215 2260);
FORCEPROP 2 LASTPIN (-225 2200) $PN 172
J 0
(-215 2210);
DISPLAY 0.617021 (-215 2210);
PAINT ORANGE (-215 2210);
FORCEPROP 2 LASTPIN (-225 2150) $PN 27
J 0
(-215 2160);
DISPLAY 0.617021 (-215 2160);
PAINT ORANGE (-215 2160);
FORCEPROP 2 LASTPIN (-225 2100) $PN 166
J 0
(-215 2110);
DISPLAY 0.617021 (-215 2110);
PAINT ORANGE (-215 2110);
FORCEPROP 2 LASTPIN (-225 2050) $PN 21
J 0
(-215 2060);
DISPLAY 0.617021 (-215 2060);
PAINT ORANGE (-215 2060);
FORCEPROP 2 LASTPIN (-225 2000) $PN 159
J 0
(-215 2010);
DISPLAY 0.617021 (-215 2010);
PAINT ORANGE (-215 2010);
FORCEPROP 2 LASTPIN (-225 1950) $PN 14
J 0
(-215 1960);
DISPLAY 0.617021 (-215 1960);
PAINT ORANGE (-215 1960);
FORCEPROP 2 LASTPIN (-225 1900) $PN 168
J 0
(-215 1910);
DISPLAY 0.617021 (-215 1910);
PAINT ORANGE (-215 1910);
FORCEPROP 2 LASTPIN (-225 1850) $PN 23
J 0
(-215 1860);
DISPLAY 0.617021 (-215 1860);
PAINT ORANGE (-215 1860);
FORCEPROP 2 LASTPIN (-225 1800) $PN 161
J 0
(-215 1810);
DISPLAY 0.617021 (-215 1810);
PAINT ORANGE (-215 1810);
FORCEPROP 2 LASTPIN (-225 1750) $PN 16
J 0
(-215 1760);
DISPLAY 0.617021 (-215 1760);
PAINT ORANGE (-215 1760);
FORCEPROP 2 LASTPIN (-225 1700) $PN 155
J 0
(-215 1710);
DISPLAY 0.617021 (-215 1710);
PAINT ORANGE (-215 1710);
FORCEPROP 2 LASTPIN (-225 1650) $PN 10
J 0
(-215 1660);
DISPLAY 0.617021 (-215 1660);
PAINT ORANGE (-215 1660);
FORCEPROP 2 LASTPIN (-225 1600) $PN 148
J 0
(-215 1610);
DISPLAY 0.617021 (-215 1610);
PAINT ORANGE (-215 1610);
FORCEPROP 2 LASTPIN (-225 1550) $PN 3
J 0
(-215 1560);
DISPLAY 0.617021 (-215 1560);
PAINT ORANGE (-215 1560);
FORCEPROP 2 LASTPIN (-225 1500) $PN 157
J 0
(-215 1510);
DISPLAY 0.617021 (-215 1510);
PAINT ORANGE (-215 1510);
FORCEPROP 2 LASTPIN (-225 1450) $PN 12
J 0
(-215 1460);
DISPLAY 0.617021 (-215 1460);
PAINT ORANGE (-215 1460);
FORCEPROP 2 LASTPIN (-225 1400) $PN 150
J 0
(-215 1410);
DISPLAY 0.617021 (-215 1410);
PAINT ORANGE (-215 1410);
FORCEPROP 2 LASTPIN (-225 1350) $PN 5
J 0
(-215 1360);
DISPLAY 0.617021 (-215 1360);
PAINT ORANGE (-215 1360);
FORCEPROP 2 LASTPIN (-1225 2750) $PN 203
J 2
(-1235 2760);
DISPLAY 0.617021 (-1235 2760);
PAINT ORANGE (-1235 2760);
FORCEPROP 2 LASTPIN (-1225 2700) $PN 60
J 2
(-1235 2710);
DISPLAY 0.617021 (-1235 2710);
PAINT ORANGE (-1235 2710);
FORCEPROP 2 LASTPIN (-1225 3300) $PN 218
J 2
(-1235 3310);
DISPLAY 0.617021 (-1235 3310);
PAINT ORANGE (-1235 3310);
FORCEPROP 2 LASTPIN (-1225 3250) $PN 219
J 2
(-1235 3260);
DISPLAY 0.617021 (-1235 3260);
PAINT ORANGE (-1235 3260);
FORCEPROP 2 LASTPIN (-1225 3200) $PN 74
J 2
(-1235 3210);
DISPLAY 0.617021 (-1235 3210);
PAINT ORANGE (-1235 3210);
FORCEPROP 2 LASTPIN (-1225 3150) $PN 75
J 2
(-1235 3160);
DISPLAY 0.617021 (-1235 3160);
PAINT ORANGE (-1235 3160);
FORCEPROP 2 LASTPIN (-1225 2450) $PN 199
J 2
(-1235 2460);
DISPLAY 0.617021 (-1235 2460);
PAINT ORANGE (-1235 2460);
FORCEPROP 2 LASTPIN (-1225 2400) $PN 54
J 2
(-1235 2410);
DISPLAY 0.617021 (-1235 2410);
PAINT ORANGE (-1235 2410);
FORCEPROP 2 LASTPIN (-1225 2350) $PN 192
J 2
(-1235 2360);
DISPLAY 0.617021 (-1235 2360);
PAINT ORANGE (-1235 2360);
FORCEPROP 2 LASTPIN (-1225 2300) $PN 47
J 2
(-1235 2310);
DISPLAY 0.617021 (-1235 2310);
PAINT ORANGE (-1235 2310);
FORCEPROP 2 LASTPIN (-1225 2250) $PN 201
J 2
(-1235 2260);
DISPLAY 0.617021 (-1235 2260);
PAINT ORANGE (-1235 2260);
FORCEPROP 2 LASTPIN (-1225 2200) $PN 56
J 2
(-1235 2210);
DISPLAY 0.617021 (-1235 2210);
PAINT ORANGE (-1235 2210);
FORCEPROP 2 LASTPIN (-1225 2150) $PN 194
J 2
(-1235 2160);
DISPLAY 0.617021 (-1235 2160);
PAINT ORANGE (-1235 2160);
FORCEPROP 2 LASTPIN (-1225 2100) $PN 49
J 2
(-1235 2110);
DISPLAY 0.617021 (-1235 2110);
PAINT ORANGE (-1235 2110);
FORCEPROP 2 LASTPIN (-1225 3050) $PN 235
J 2
(-1235 3060);
DISPLAY 0.617021 (-1235 3060);
PAINT ORANGE (-1235 3060);
FORCEPROP 2 LASTPIN (-1225 3450) $PN 207
J 2
(-1235 3460);
DISPLAY 0.617021 (-1235 3460);
PAINT ORANGE (-1235 3460);
FORCEPROP 2 LASTPIN (-1225 3400) $PN 63
J 2
(-1235 3410);
DISPLAY 0.617021 (-1235 3410);
PAINT ORANGE (-1235 3410);
FORCEPROP 2 LASTPIN (-1225 3550) $PN 224
J 2
(-1235 3560);
DISPLAY 0.617021 (-1235 3560);
PAINT ORANGE (-1235 3560);
FORCEPROP 2 LASTPIN (-1225 3500) $PN 81
J 2
(-1235 3510);
DISPLAY 0.617021 (-1235 3510);
PAINT ORANGE (-1235 3510);
FORCEPROP 2 LASTPIN (-1225 1850) $PN 208
J 2
(-1235 1860);
DISPLAY 0.617021 (-1235 1860);
PAINT ORANGE (-1235 1860);
FORCEPROP 2 LASTPIN (-1225 1800) $PN 62
J 2
(-1235 1810);
DISPLAY 0.617021 (-1235 1810);
PAINT ORANGE (-1235 1810);
FORCEPROP 2 LASTPIN (-1225 4500) $PN 234
J 2
(-1235 4510);
DISPLAY 0.617021 (-1235 4510);
PAINT ORANGE (-1235 4510);
FORCEPROP 2 LASTPIN (-1225 4450) $PN 82
J 2
(-1235 4460);
DISPLAY 0.617021 (-1235 4460);
PAINT ORANGE (-1235 4460);
FORCEPROP 2 LASTPIN (-1225 4400) $PN 86
J 2
(-1235 4410);
DISPLAY 0.617021 (-1235 4410);
PAINT ORANGE (-1235 4410);
FORCEPROP 2 LASTPIN (-1225 4350) $PN 228
J 2
(-1235 4360);
DISPLAY 0.617021 (-1235 4360);
PAINT ORANGE (-1235 4360);
FORCEPROP 2 LASTPIN (-1225 4300) $PN 232
J 2
(-1235 4310);
DISPLAY 0.617021 (-1235 4310);
PAINT ORANGE (-1235 4310);
FORCEPROP 2 LASTPIN (-1225 4250) $PN 65
J 2
(-1235 4260);
DISPLAY 0.617021 (-1235 4260);
PAINT ORANGE (-1235 4260);
FORCEPROP 2 LASTPIN (-1225 4200) $PN 210
J 2
(-1235 4210);
DISPLAY 0.617021 (-1235 4210);
PAINT ORANGE (-1235 4210);
FORCEPROP 2 LASTPIN (-1225 4150) $PN 225
J 2
(-1235 4160);
DISPLAY 0.617021 (-1235 4160);
PAINT ORANGE (-1235 4160);
FORCEPROP 2 LASTPIN (-1225 4100) $PN 66
J 2
(-1235 4110);
DISPLAY 0.617021 (-1235 4110);
PAINT ORANGE (-1235 4110);
FORCEPROP 2 LASTPIN (-1225 4050) $PN 68
J 2
(-1235 4060);
DISPLAY 0.617021 (-1235 4060);
PAINT ORANGE (-1235 4060);
FORCEPROP 2 LASTPIN (-1225 4000) $PN 211
J 2
(-1235 4010);
DISPLAY 0.617021 (-1235 4010);
PAINT ORANGE (-1235 4010);
FORCEPROP 2 LASTPIN (-1225 3950) $PN 69
J 2
(-1235 3960);
DISPLAY 0.617021 (-1235 3960);
PAINT ORANGE (-1235 3960);
FORCEPROP 2 LASTPIN (-1225 3900) $PN 213
J 2
(-1235 3910);
DISPLAY 0.617021 (-1235 3910);
PAINT ORANGE (-1235 3910);
FORCEPROP 2 LASTPIN (-1225 3850) $PN 214
J 2
(-1235 3860);
DISPLAY 0.617021 (-1235 3860);
PAINT ORANGE (-1235 3860);
FORCEPROP 2 LASTPIN (-1225 3800) $PN 71
J 2
(-1235 3810);
DISPLAY 0.617021 (-1235 3810);
PAINT ORANGE (-1235 3810);
FORCEPROP 2 LASTPIN (-1225 3750) $PN 216
J 2
(-1235 3760);
DISPLAY 0.617021 (-1235 3760);
PAINT ORANGE (-1235 3760);
FORCEPROP 2 LASTPIN (-1225 3700) $PN 72
J 2
(-1235 3710);
DISPLAY 0.617021 (-1235 3710);
PAINT ORANGE (-1235 3710);
FORCEPROP 2 LASTPIN (-1225 3650) $PN 79
J 2
(-1235 3660);
DISPLAY 0.617021 (-1235 3660);
PAINT ORANGE (-1235 3660);
FORCEPROP 1 LAST PACK_TYPE PIP
J 0
(-1175 4800);
PAINT SKYBLUE (-1175 4800);
DISPLAY INVISIBLE (-1175 4800);
FORCEPROP 2 LAST BOM_COST MEM
J 0
(-1175 4800);
PAINT MONO (-1175 4800);
DISPLAY INVISIBLE (-1175 4800);
FORCEPROP 2 LAST CDS_LIB mstr_sconn
J 0
(-725 2850);
PAINT ORANGE (-725 2850);
DISPLAY INVISIBLE (-725 2850);
FORCEPROP 2 LAST SEC_TYPE PIP
J 0
(-1175 4800);
DISPLAY 1.021277 (-1175 4800);
PAINT ORANGE (-1175 4800);
DISPLAY INVISIBLE (-1175 4800);
FORCEPROP 2 LAST SEC 1
J 0
(-1175 4800);
DISPLAY 0.680851 (-1175 4800);
PAINT MONO (-1175 4800);
DISPLAY INVISIBLE (-1175 4800);
FORCEPROP 2 LAST CDS_LOCATION J6L2
J 0
(-1175 4750);
DISPLAY 0.617021 (-1175 4750);
PAINT AQUA (-1175 4750);
DISPLAY INVISIBLE (-1175 4750);
FORCEPROP 1 LAST PATH I12
J 0
(-725 4700);
PAINT GREEN (-725 4700);
DISPLAY INVISIBLE (-725 4700);
FORCEPROP 0 LAST ROOM DDR4_CH_E
J 0
(-1175 4850);
DISPLAY 1.021277 (-1175 4850);
PAINT ORANGE (-1175 4850);
DISPLAY INVISIBLE (-1175 4850);
FORCEADD TAP..6
R 2
(25 3700);
FORCEPROP 3 LASTPIN (-25 3700) SIG_NAME M_E_DQ<47>
J 0
(-15 3710);
DISPLAY 0.659574 (-15 3710);
PAINT MONO (-15 3710);
DISPLAY INVISIBLE (-15 3710);
FORCEPROP 1 LASTPIN (-25 3700) BN 47
J 2
(25 3710);
DISPLAY 0.617021 (25 3710);
PAINT PINK (25 3710);
FORCEPROP 2 LAST CDS_LIB mstr_standard
J 2
(25 3700);
DISPLAY 0.787234 (25 3700);
PAINT MONO (25 3700);
DISPLAY INVISIBLE (25 3700);
FORCEPROP 1 LAST BODY_TYPE PLUMBING
J 2
(25 3650);
DISPLAY 1.234043 (25 3650);
PAINT GREEN (25 3650);
DISPLAY INVISIBLE (25 3650);
FORCEPROP 1 LAST HDL_TAP TRUE
J 2
(-300 3575);
DISPLAY 1.234043 (-300 3575);
PAINT GREEN (-300 3575);
DISPLAY INVISIBLE (-300 3575);
FORCEPROP 1 LAST PATH I120
J 2
(27 3700);
DISPLAY 0.872340 (27 3700);
PAINT GREEN (27 3700);
DISPLAY INVISIBLE (27 3700);
FORCEADD TAP..6
R 2
(25 3750);
FORCEPROP 3 LASTPIN (-25 3750) SIG_NAME M_E_DQ<48>
J 0
(-15 3760);
DISPLAY 0.659574 (-15 3760);
PAINT MONO (-15 3760);
DISPLAY INVISIBLE (-15 3760);
FORCEPROP 1 LASTPIN (-25 3750) BN 48
J 2
(25 3760);
DISPLAY 0.617021 (25 3760);
PAINT PINK (25 3760);
FORCEPROP 2 LAST CDS_LIB mstr_standard
J 2
(25 3750);
DISPLAY 0.787234 (25 3750);
PAINT MONO (25 3750);
DISPLAY INVISIBLE (25 3750);
FORCEPROP 1 LAST BODY_TYPE PLUMBING
J 2
(25 3700);
DISPLAY 1.234043 (25 3700);
PAINT GREEN (25 3700);
DISPLAY INVISIBLE (25 3700);
FORCEPROP 1 LAST HDL_TAP TRUE
J 2
(-300 3625);
DISPLAY 1.234043 (-300 3625);
PAINT GREEN (-300 3625);
DISPLAY INVISIBLE (-300 3625);
FORCEPROP 1 LAST PATH I121
J 2
(27 3750);
DISPLAY 0.872340 (27 3750);
PAINT GREEN (27 3750);
DISPLAY INVISIBLE (27 3750);
FORCEADD TAP..6
R 2
(25 3950);
FORCEPROP 3 LASTPIN (-25 3950) SIG_NAME M_E_DQ<52>
J 0
(-15 3960);
DISPLAY 0.659574 (-15 3960);
PAINT MONO (-15 3960);
DISPLAY INVISIBLE (-15 3960);
FORCEPROP 1 LASTPIN (-25 3950) BN 52
J 2
(25 3960);
DISPLAY 0.617021 (25 3960);
PAINT PINK (25 3960);
FORCEPROP 2 LAST CDS_LIB mstr_standard
J 2
(25 3950);
DISPLAY 0.787234 (25 3950);
PAINT MONO (25 3950);
DISPLAY INVISIBLE (25 3950);
FORCEPROP 1 LAST BODY_TYPE PLUMBING
J 2
(25 3900);
DISPLAY 1.234043 (25 3900);
PAINT GREEN (25 3900);
DISPLAY INVISIBLE (25 3900);
FORCEPROP 1 LAST HDL_TAP TRUE
J 2
(-300 3825);
DISPLAY 1.234043 (-300 3825);
PAINT GREEN (-300 3825);
DISPLAY INVISIBLE (-300 3825);
FORCEPROP 1 LAST PATH I122
J 2
(27 3950);
DISPLAY 0.872340 (27 3950);
PAINT GREEN (27 3950);
DISPLAY INVISIBLE (27 3950);
FORCEADD TAP..6
R 2
(25 3900);
FORCEPROP 3 LASTPIN (-25 3900) SIG_NAME M_E_DQ<51>
J 0
(-15 3910);
DISPLAY 0.659574 (-15 3910);
PAINT MONO (-15 3910);
DISPLAY INVISIBLE (-15 3910);
FORCEPROP 1 LASTPIN (-25 3900) BN 51
J 2
(25 3910);
DISPLAY 0.617021 (25 3910);
PAINT PINK (25 3910);
FORCEPROP 2 LAST CDS_LIB mstr_standard
J 2
(25 3900);
DISPLAY 0.787234 (25 3900);
PAINT MONO (25 3900);
DISPLAY INVISIBLE (25 3900);
FORCEPROP 1 LAST BODY_TYPE PLUMBING
J 2
(25 3850);
DISPLAY 1.234043 (25 3850);
PAINT GREEN (25 3850);
DISPLAY INVISIBLE (25 3850);
FORCEPROP 1 LAST HDL_TAP TRUE
J 2
(-300 3775);
DISPLAY 1.234043 (-300 3775);
PAINT GREEN (-300 3775);
DISPLAY INVISIBLE (-300 3775);
FORCEPROP 1 LAST PATH I123
J 2
(27 3900);
DISPLAY 0.872340 (27 3900);
PAINT GREEN (27 3900);
DISPLAY INVISIBLE (27 3900);
FORCEADD TAP..6
R 2
(25 3850);
FORCEPROP 3 LASTPIN (-25 3850) SIG_NAME M_E_DQ<50>
J 0
(-15 3860);
DISPLAY 0.659574 (-15 3860);
PAINT MONO (-15 3860);
DISPLAY INVISIBLE (-15 3860);
FORCEPROP 1 LASTPIN (-25 3850) BN 50
J 2
(25 3860);
DISPLAY 0.617021 (25 3860);
PAINT PINK (25 3860);
FORCEPROP 2 LAST CDS_LIB mstr_standard
J 2
(25 3850);
DISPLAY 0.787234 (25 3850);
PAINT MONO (25 3850);
DISPLAY INVISIBLE (25 3850);
FORCEPROP 1 LAST BODY_TYPE PLUMBING
J 2
(25 3800);
DISPLAY 1.234043 (25 3800);
PAINT GREEN (25 3800);
DISPLAY INVISIBLE (25 3800);
FORCEPROP 1 LAST HDL_TAP TRUE
J 2
(-300 3725);
DISPLAY 1.234043 (-300 3725);
PAINT GREEN (-300 3725);
DISPLAY INVISIBLE (-300 3725);
FORCEPROP 1 LAST PATH I124
J 2
(27 3850);
DISPLAY 0.872340 (27 3850);
PAINT GREEN (27 3850);
DISPLAY INVISIBLE (27 3850);
FORCEADD TAP..6
R 2
(25 4000);
FORCEPROP 3 LASTPIN (-25 4000) SIG_NAME M_E_DQ<53>
J 0
(-15 4010);
DISPLAY 0.659574 (-15 4010);
PAINT MONO (-15 4010);
DISPLAY INVISIBLE (-15 4010);
FORCEPROP 1 LASTPIN (-25 4000) BN 53
J 2
(25 4010);
DISPLAY 0.617021 (25 4010);
PAINT PINK (25 4010);
FORCEPROP 2 LAST CDS_LIB mstr_standard
J 2
(25 4000);
DISPLAY 0.787234 (25 4000);
PAINT MONO (25 4000);
DISPLAY INVISIBLE (25 4000);
FORCEPROP 1 LAST BODY_TYPE PLUMBING
J 2
(25 3950);
DISPLAY 1.234043 (25 3950);
PAINT GREEN (25 3950);
DISPLAY INVISIBLE (25 3950);
FORCEPROP 1 LAST HDL_TAP TRUE
J 2
(-300 3875);
DISPLAY 1.234043 (-300 3875);
PAINT GREEN (-300 3875);
DISPLAY INVISIBLE (-300 3875);
FORCEPROP 1 LAST PATH I125
J 2
(27 4000);
DISPLAY 0.872340 (27 4000);
PAINT GREEN (27 4000);
DISPLAY INVISIBLE (27 4000);
FORCEADD TAP..6
R 2
(25 4050);
FORCEPROP 3 LASTPIN (-25 4050) SIG_NAME M_E_DQ<54>
J 0
(-15 4060);
DISPLAY 0.659574 (-15 4060);
PAINT MONO (-15 4060);
DISPLAY INVISIBLE (-15 4060);
FORCEPROP 1 LASTPIN (-25 4050) BN 54
J 2
(25 4060);
DISPLAY 0.617021 (25 4060);
PAINT PINK (25 4060);
FORCEPROP 2 LAST CDS_LIB mstr_standard
J 2
(25 4050);
DISPLAY 0.787234 (25 4050);
PAINT MONO (25 4050);
DISPLAY INVISIBLE (25 4050);
FORCEPROP 1 LAST BODY_TYPE PLUMBING
J 2
(25 4000);
DISPLAY 1.234043 (25 4000);
PAINT GREEN (25 4000);
DISPLAY INVISIBLE (25 4000);
FORCEPROP 1 LAST HDL_TAP TRUE
J 2
(-300 3925);
DISPLAY 1.234043 (-300 3925);
PAINT GREEN (-300 3925);
DISPLAY INVISIBLE (-300 3925);
FORCEPROP 1 LAST PATH I126
J 2
(27 4050);
DISPLAY 0.872340 (27 4050);
PAINT GREEN (27 4050);
DISPLAY INVISIBLE (27 4050);
FORCEADD TAP..6
R 2
(25 4200);
FORCEPROP 3 LASTPIN (-25 4200) SIG_NAME M_E_DQ<57>
J 0
(-15 4210);
DISPLAY 0.659574 (-15 4210);
PAINT MONO (-15 4210);
DISPLAY INVISIBLE (-15 4210);
FORCEPROP 1 LASTPIN (-25 4200) BN 57
J 2
(25 4210);
DISPLAY 0.617021 (25 4210);
PAINT PINK (25 4210);
FORCEPROP 2 LAST CDS_LIB mstr_standard
J 2
(25 4200);
DISPLAY 0.787234 (25 4200);
PAINT MONO (25 4200);
DISPLAY INVISIBLE (25 4200);
FORCEPROP 1 LAST BODY_TYPE PLUMBING
J 2
(25 4150);
DISPLAY 1.234043 (25 4150);
PAINT GREEN (25 4150);
DISPLAY INVISIBLE (25 4150);
FORCEPROP 1 LAST HDL_TAP TRUE
J 2
(-300 4075);
DISPLAY 1.234043 (-300 4075);
PAINT GREEN (-300 4075);
DISPLAY INVISIBLE (-300 4075);
FORCEPROP 1 LAST PATH I127
J 2
(27 4200);
DISPLAY 0.872340 (27 4200);
PAINT GREEN (27 4200);
DISPLAY INVISIBLE (27 4200);
FORCEADD TAP..6
R 2
(25 4150);
FORCEPROP 3 LASTPIN (-25 4150) SIG_NAME M_E_DQ<56>
J 0
(-15 4160);
DISPLAY 0.659574 (-15 4160);
PAINT MONO (-15 4160);
DISPLAY INVISIBLE (-15 4160);
FORCEPROP 1 LASTPIN (-25 4150) BN 56
J 2
(25 4160);
DISPLAY 0.617021 (25 4160);
PAINT PINK (25 4160);
FORCEPROP 2 LAST CDS_LIB mstr_standard
J 2
(25 4150);
DISPLAY 0.787234 (25 4150);
PAINT MONO (25 4150);
DISPLAY INVISIBLE (25 4150);
FORCEPROP 1 LAST BODY_TYPE PLUMBING
J 2
(25 4100);
DISPLAY 1.234043 (25 4100);
PAINT GREEN (25 4100);
DISPLAY INVISIBLE (25 4100);
FORCEPROP 1 LAST HDL_TAP TRUE
J 2
(-300 4025);
DISPLAY 1.234043 (-300 4025);
PAINT GREEN (-300 4025);
DISPLAY INVISIBLE (-300 4025);
FORCEPROP 1 LAST PATH I128
J 2
(27 4150);
DISPLAY 0.872340 (27 4150);
PAINT GREEN (27 4150);
DISPLAY INVISIBLE (27 4150);
FORCEADD TAP..6
R 2
(25 4100);
FORCEPROP 3 LASTPIN (-25 4100) SIG_NAME M_E_DQ<55>
J 0
(-15 4110);
DISPLAY 0.659574 (-15 4110);
PAINT MONO (-15 4110);
DISPLAY INVISIBLE (-15 4110);
FORCEPROP 1 LASTPIN (-25 4100) BN 55
J 2
(25 4110);
DISPLAY 0.617021 (25 4110);
PAINT PINK (25 4110);
FORCEPROP 2 LAST CDS_LIB mstr_standard
J 2
(25 4100);
DISPLAY 0.787234 (25 4100);
PAINT MONO (25 4100);
DISPLAY INVISIBLE (25 4100);
FORCEPROP 1 LAST BODY_TYPE PLUMBING
J 2
(25 4050);
DISPLAY 1.234043 (25 4050);
PAINT GREEN (25 4050);
DISPLAY INVISIBLE (25 4050);
FORCEPROP 1 LAST HDL_TAP TRUE
J 2
(-300 3975);
DISPLAY 1.234043 (-300 3975);
PAINT GREEN (-300 3975);
DISPLAY INVISIBLE (-300 3975);
FORCEPROP 1 LAST PATH I129
J 2
(27 4100);
DISPLAY 0.872340 (27 4100);
PAINT GREEN (27 4100);
DISPLAY INVISIBLE (27 4100);
FORCEADD OFFPAGE..5
(-2300 1850);
FORCEPROP 2 LAST $XR0 51 
J 0
(-2524 1850);
DISPLAY 0.638298 (-2524 1850);
PAINT MONO (-2524 1850);
FORCEPROP 2 LAST $XR1 27 
J 0
(-2614 1850);
DISPLAY 0.638298 (-2614 1850);
PAINT MONO (-2614 1850);
FORCEPROP 2 LAST CDS_LIB mstr_standard
J 0
(-2300 1850);
DISPLAY 0.787234 (-2300 1850);
PAINT MONO (-2300 1850);
DISPLAY INVISIBLE (-2300 1850);
FORCEPROP 1 LAST OFFPAGE TRUE
J 0
(-1975 1725);
DISPLAY 1.404255 (-1975 1725);
PAINT GREEN (-1975 1725);
DISPLAY INVISIBLE (-1975 1725);
FORCEPROP 1 LAST COMMENT_BODY TRUE
J 0
(-2200 1775);
DISPLAY 1.404255 (-2200 1775);
PAINT GREEN (-2200 1775);
DISPLAY INVISIBLE (-2200 1775);
FORCEPROP 2 LAST PATH I13
J 0
(-2550 1900);
DISPLAY 1.021277 (-2550 1900);
PAINT ORANGE (-2550 1900);
DISPLAY INVISIBLE (-2550 1900);
FORCEADD TAP..6
R 2
(25 4300);
FORCEPROP 3 LASTPIN (-25 4300) SIG_NAME M_E_DQ<59>
J 0
(-15 4310);
DISPLAY 0.659574 (-15 4310);
PAINT MONO (-15 4310);
DISPLAY INVISIBLE (-15 4310);
FORCEPROP 1 LASTPIN (-25 4300) BN 59
J 2
(25 4310);
DISPLAY 0.617021 (25 4310);
PAINT PINK (25 4310);
FORCEPROP 2 LAST CDS_LIB mstr_standard
J 2
(25 4300);
DISPLAY 0.787234 (25 4300);
PAINT MONO (25 4300);
DISPLAY INVISIBLE (25 4300);
FORCEPROP 1 LAST BODY_TYPE PLUMBING
J 2
(25 4250);
DISPLAY 1.234043 (25 4250);
PAINT GREEN (25 4250);
DISPLAY INVISIBLE (25 4250);
FORCEPROP 1 LAST HDL_TAP TRUE
J 2
(-300 4175);
DISPLAY 1.234043 (-300 4175);
PAINT GREEN (-300 4175);
DISPLAY INVISIBLE (-300 4175);
FORCEPROP 1 LAST PATH I130
J 2
(27 4300);
DISPLAY 0.872340 (27 4300);
PAINT GREEN (27 4300);
DISPLAY INVISIBLE (27 4300);
FORCEADD TAP..6
R 2
(25 4250);
FORCEPROP 3 LASTPIN (-25 4250) SIG_NAME M_E_DQ<58>
J 0
(-15 4260);
DISPLAY 0.659574 (-15 4260);
PAINT MONO (-15 4260);
DISPLAY INVISIBLE (-15 4260);
FORCEPROP 1 LASTPIN (-25 4250) BN 58
J 2
(25 4260);
DISPLAY 0.617021 (25 4260);
PAINT PINK (25 4260);
FORCEPROP 2 LAST CDS_LIB mstr_standard
J 2
(25 4250);
DISPLAY 0.787234 (25 4250);
PAINT MONO (25 4250);
DISPLAY INVISIBLE (25 4250);
FORCEPROP 1 LAST BODY_TYPE PLUMBING
J 2
(25 4200);
DISPLAY 1.234043 (25 4200);
PAINT GREEN (25 4200);
DISPLAY INVISIBLE (25 4200);
FORCEPROP 1 LAST HDL_TAP TRUE
J 2
(-300 4125);
DISPLAY 1.234043 (-300 4125);
PAINT GREEN (-300 4125);
DISPLAY INVISIBLE (-300 4125);
FORCEPROP 1 LAST PATH I131
J 2
(27 4250);
DISPLAY 0.872340 (27 4250);
PAINT GREEN (27 4250);
DISPLAY INVISIBLE (27 4250);
FORCEADD TAP..6
R 2
(25 4450);
FORCEPROP 3 LASTPIN (-25 4450) SIG_NAME M_E_DQ<62>
J 0
(-15 4460);
DISPLAY 0.659574 (-15 4460);
PAINT MONO (-15 4460);
DISPLAY INVISIBLE (-15 4460);
FORCEPROP 1 LASTPIN (-25 4450) BN 62
J 2
(25 4460);
DISPLAY 0.617021 (25 4460);
PAINT PINK (25 4460);
FORCEPROP 2 LAST CDS_LIB mstr_standard
J 2
(25 4450);
DISPLAY 0.787234 (25 4450);
PAINT MONO (25 4450);
DISPLAY INVISIBLE (25 4450);
FORCEPROP 1 LAST BODY_TYPE PLUMBING
J 2
(25 4400);
DISPLAY 1.234043 (25 4400);
PAINT GREEN (25 4400);
DISPLAY INVISIBLE (25 4400);
FORCEPROP 1 LAST HDL_TAP TRUE
J 2
(-300 4325);
DISPLAY 1.234043 (-300 4325);
PAINT GREEN (-300 4325);
DISPLAY INVISIBLE (-300 4325);
FORCEPROP 1 LAST PATH I132
J 2
(27 4450);
DISPLAY 0.872340 (27 4450);
PAINT GREEN (27 4450);
DISPLAY INVISIBLE (27 4450);
FORCEADD TAP..6
R 2
(25 4350);
FORCEPROP 3 LASTPIN (-25 4350) SIG_NAME M_E_DQ<60>
J 0
(-15 4360);
DISPLAY 0.659574 (-15 4360);
PAINT MONO (-15 4360);
DISPLAY INVISIBLE (-15 4360);
FORCEPROP 1 LASTPIN (-25 4350) BN 60
J 2
(25 4360);
DISPLAY 0.617021 (25 4360);
PAINT PINK (25 4360);
FORCEPROP 2 LAST CDS_LIB mstr_standard
J 2
(25 4350);
DISPLAY 0.787234 (25 4350);
PAINT MONO (25 4350);
DISPLAY INVISIBLE (25 4350);
FORCEPROP 1 LAST BODY_TYPE PLUMBING
J 2
(25 4300);
DISPLAY 1.234043 (25 4300);
PAINT GREEN (25 4300);
DISPLAY INVISIBLE (25 4300);
FORCEPROP 1 LAST HDL_TAP TRUE
J 2
(-300 4225);
DISPLAY 1.234043 (-300 4225);
PAINT GREEN (-300 4225);
DISPLAY INVISIBLE (-300 4225);
FORCEPROP 1 LAST PATH I133
J 2
(27 4350);
DISPLAY 0.872340 (27 4350);
PAINT GREEN (27 4350);
DISPLAY INVISIBLE (27 4350);
FORCEADD TAP..6
R 2
(25 4400);
FORCEPROP 3 LASTPIN (-25 4400) SIG_NAME M_E_DQ<61>
J 0
(-15 4410);
DISPLAY 0.659574 (-15 4410);
PAINT MONO (-15 4410);
DISPLAY INVISIBLE (-15 4410);
FORCEPROP 1 LASTPIN (-25 4400) BN 61
J 2
(25 4410);
DISPLAY 0.617021 (25 4410);
PAINT PINK (25 4410);
FORCEPROP 2 LAST CDS_LIB mstr_standard
J 2
(25 4400);
DISPLAY 0.787234 (25 4400);
PAINT MONO (25 4400);
DISPLAY INVISIBLE (25 4400);
FORCEPROP 1 LAST BODY_TYPE PLUMBING
J 2
(25 4350);
DISPLAY 1.234043 (25 4350);
PAINT GREEN (25 4350);
DISPLAY INVISIBLE (25 4350);
FORCEPROP 1 LAST HDL_TAP TRUE
J 2
(-300 4275);
DISPLAY 1.234043 (-300 4275);
PAINT GREEN (-300 4275);
DISPLAY INVISIBLE (-300 4275);
FORCEPROP 1 LAST PATH I134
J 2
(27 4400);
DISPLAY 0.872340 (27 4400);
PAINT GREEN (27 4400);
DISPLAY INVISIBLE (27 4400);
FORCEADD TAP..6
R 2
(25 4500);
FORCEPROP 3 LASTPIN (-25 4500) SIG_NAME M_E_DQ<63>
J 0
(-15 4510);
DISPLAY 0.659574 (-15 4510);
PAINT MONO (-15 4510);
DISPLAY INVISIBLE (-15 4510);
FORCEPROP 1 LASTPIN (-25 4500) BN 63
J 2
(25 4510);
DISPLAY 0.617021 (25 4510);
PAINT PINK (25 4510);
FORCEPROP 2 LAST CDS_LIB mstr_standard
J 2
(25 4500);
DISPLAY 0.787234 (25 4500);
PAINT MONO (25 4500);
DISPLAY INVISIBLE (25 4500);
FORCEPROP 1 LAST BODY_TYPE PLUMBING
J 2
(25 4450);
DISPLAY 1.234043 (25 4450);
PAINT GREEN (25 4450);
DISPLAY INVISIBLE (25 4450);
FORCEPROP 1 LAST HDL_TAP TRUE
J 2
(-300 4375);
DISPLAY 1.234043 (-300 4375);
PAINT GREEN (-300 4375);
DISPLAY INVISIBLE (-300 4375);
FORCEPROP 1 LAST PATH I135
J 2
(27 4500);
DISPLAY 0.872340 (27 4500);
PAINT GREEN (27 4500);
DISPLAY INVISIBLE (27 4500);
FORCEADD OFFPAGE..3
(575 4550);
FORCEPROP 2 LAST $XR0 27 
J 0
(789 4550);
DISPLAY 0.638298 (789 4550);
PAINT MONO (789 4550);
FORCEPROP 2 LAST $XR1 51 
J 0
(879 4550);
DISPLAY 0.638298 (879 4550);
PAINT MONO (879 4550);
FORCEPROP 2 LAST CDS_LIB mstr_standard
J 0
(575 4550);
DISPLAY 0.787234 (575 4550);
PAINT MONO (575 4550);
DISPLAY INVISIBLE (575 4550);
FORCEPROP 1 LAST OFFPAGE TRUE
J 0
(900 4425);
DISPLAY 0.936170 (900 4425);
PAINT GREEN (900 4425);
DISPLAY INVISIBLE (900 4425);
FORCEPROP 1 LAST COMMENT_BODY TRUE
J 0
(525 4450);
DISPLAY 0.936170 (525 4450);
PAINT GREEN (525 4450);
DISPLAY INVISIBLE (525 4450);
FORCEPROP 2 LAST PATH I136
J 0
(800 4600);
DISPLAY 1.021277 (800 4600);
PAINT ORANGE (800 4600);
DISPLAY INVISIBLE (800 4600);
FORCEADD GND..1
R 2
(2725 800);
FORCEPROP 3 LASTPIN (2725 850) SIG_NAME GND\g
J 0
(2735 860);
DISPLAY 0.659574 (2735 860);
PAINT MONO (2735 860);
DISPLAY INVISIBLE (2735 860);
FORCEPROP 1 LAST VOLTAGE 0
J 0
(2725 800);
PAINT SKYBLUE (2725 800);
DISPLAY INVISIBLE (2725 800);
FORCEPROP 2 LAST CDS_LIB mstr_symbols
J 0
(2725 800);
DISPLAY 0.787234 (2725 800);
PAINT MONO (2725 800);
DISPLAY INVISIBLE (2725 800);
FORCEPROP 1 LAST SIZE 1B
J 2
(2650 750);
DISPLAY 1.170213 (2650 750);
PAINT GREEN (2650 750);
DISPLAY INVISIBLE (2650 750);
FORCEPROP 1 LAST BODY_TYPE PLUMBING
J 2
(2770 757);
DISPLAY 0.340426 (2770 757);
PAINT GREEN (2770 757);
DISPLAY INVISIBLE (2770 757);
FORCEPROP 1 LAST PATH I137
J 2
(2650 800);
DISPLAY 0.872340 (2650 800);
PAINT AQUA (2650 800);
DISPLAY INVISIBLE (2650 800);
FORCEPROP 1 LAST HDL_POWER GND
J 2
(2725 950);
DISPLAY 0.553191 (2725 950);
PAINT GREEN (2725 950);
DISPLAY INVISIBLE (2725 950);
FORCEADD SCONN288_H44441003..3
(3425 2100);
FORCEPROP 1 LAST LOCATION J6L2
J 0
(2975 3500);
DISPLAY 0.617021 (2975 3500);
PAINT AQUA (2975 3500);
FORCEPROP 1 LAST PART_NUMBER H44441-003
J 0
(2975 750);
DISPLAY 0.617021 (2975 750);
PAINT BLUE (2975 750);
FORCEPROP 1 LAST MATERIAL SCONN
J 0
(2975 3450);
DISPLAY 0.617021 (2975 3450);
PAINT SKYBLUE (2975 3450);
FORCEPROP 2 LASTPIN (2925 3250) $PN 2
J 2
(2915 3260);
DISPLAY 0.617021 (2915 3260);
PAINT ORANGE (2915 3260);
FORCEPROP 2 LASTPIN (2925 3200) $PN 4
J 2
(2915 3210);
DISPLAY 0.617021 (2915 3210);
PAINT ORANGE (2915 3210);
FORCEPROP 2 LASTPIN (2925 3150) $PN 6
J 2
(2915 3160);
DISPLAY 0.617021 (2915 3160);
PAINT ORANGE (2915 3160);
FORCEPROP 2 LASTPIN (2925 3100) $PN 9
J 2
(2915 3110);
DISPLAY 0.617021 (2915 3110);
PAINT ORANGE (2915 3110);
FORCEPROP 2 LASTPIN (2925 3050) $PN 11
J 2
(2915 3060);
DISPLAY 0.617021 (2915 3060);
PAINT ORANGE (2915 3060);
FORCEPROP 2 LASTPIN (2925 3000) $PN 13
J 2
(2915 3010);
DISPLAY 0.617021 (2915 3010);
PAINT ORANGE (2915 3010);
FORCEPROP 2 LASTPIN (2925 2950) $PN 15
J 2
(2915 2960);
DISPLAY 0.617021 (2915 2960);
PAINT ORANGE (2915 2960);
FORCEPROP 2 LASTPIN (2925 2900) $PN 17
J 2
(2915 2910);
DISPLAY 0.617021 (2915 2910);
PAINT ORANGE (2915 2910);
FORCEPROP 2 LASTPIN (2925 2850) $PN 20
J 2
(2915 2860);
DISPLAY 0.617021 (2915 2860);
PAINT ORANGE (2915 2860);
FORCEPROP 2 LASTPIN (2925 2800) $PN 22
J 2
(2915 2810);
DISPLAY 0.617021 (2915 2810);
PAINT ORANGE (2915 2810);
FORCEPROP 2 LASTPIN (2925 2750) $PN 24
J 2
(2915 2760);
DISPLAY 0.617021 (2915 2760);
PAINT ORANGE (2915 2760);
FORCEPROP 2 LASTPIN (2925 2700) $PN 26
J 2
(2915 2710);
DISPLAY 0.617021 (2915 2710);
PAINT ORANGE (2915 2710);
FORCEPROP 2 LASTPIN (2925 2650) $PN 28
J 2
(2915 2660);
DISPLAY 0.617021 (2915 2660);
PAINT ORANGE (2915 2660);
FORCEPROP 2 LASTPIN (2925 2600) $PN 31
J 2
(2915 2610);
DISPLAY 0.617021 (2915 2610);
PAINT ORANGE (2915 2610);
FORCEPROP 2 LASTPIN (2925 2550) $PN 33
J 2
(2915 2560);
DISPLAY 0.617021 (2915 2560);
PAINT ORANGE (2915 2560);
FORCEPROP 2 LASTPIN (2925 2500) $PN 35
J 2
(2915 2510);
DISPLAY 0.617021 (2915 2510);
PAINT ORANGE (2915 2510);
FORCEPROP 2 LASTPIN (2925 2450) $PN 37
J 2
(2915 2460);
DISPLAY 0.617021 (2915 2460);
PAINT ORANGE (2915 2460);
FORCEPROP 2 LASTPIN (2925 2400) $PN 39
J 2
(2915 2410);
DISPLAY 0.617021 (2915 2410);
PAINT ORANGE (2915 2410);
FORCEPROP 2 LASTPIN (2925 2350) $PN 42
J 2
(2915 2360);
DISPLAY 0.617021 (2915 2360);
PAINT ORANGE (2915 2360);
FORCEPROP 2 LASTPIN (2925 2300) $PN 44
J 2
(2915 2310);
DISPLAY 0.617021 (2915 2310);
PAINT ORANGE (2915 2310);
FORCEPROP 2 LASTPIN (2925 2250) $PN 46
J 2
(2915 2260);
DISPLAY 0.617021 (2915 2260);
PAINT ORANGE (2915 2260);
FORCEPROP 2 LASTPIN (2925 2200) $PN 48
J 2
(2915 2210);
DISPLAY 0.617021 (2915 2210);
PAINT ORANGE (2915 2210);
FORCEPROP 2 LASTPIN (2925 2150) $PN 50
J 2
(2915 2160);
DISPLAY 0.617021 (2915 2160);
PAINT ORANGE (2915 2160);
FORCEPROP 2 LASTPIN (2925 2100) $PN 53
J 2
(2915 2110);
DISPLAY 0.617021 (2915 2110);
PAINT ORANGE (2915 2110);
FORCEPROP 2 LASTPIN (2925 2050) $PN 55
J 2
(2915 2060);
DISPLAY 0.617021 (2915 2060);
PAINT ORANGE (2915 2060);
FORCEPROP 2 LASTPIN (2925 2000) $PN 57
J 2
(2915 2010);
DISPLAY 0.617021 (2915 2010);
PAINT ORANGE (2915 2010);
FORCEPROP 2 LASTPIN (2925 1950) $PN 94
J 2
(2915 1960);
DISPLAY 0.617021 (2915 1960);
PAINT ORANGE (2915 1960);
FORCEPROP 2 LASTPIN (2925 1900) $PN 96
J 2
(2915 1910);
DISPLAY 0.617021 (2915 1910);
PAINT ORANGE (2915 1910);
FORCEPROP 2 LASTPIN (2925 1850) $PN 98
J 2
(2915 1860);
DISPLAY 0.617021 (2915 1860);
PAINT ORANGE (2915 1860);
FORCEPROP 2 LASTPIN (2925 1800) $PN 101
J 2
(2915 1810);
DISPLAY 0.617021 (2915 1810);
PAINT ORANGE (2915 1810);
FORCEPROP 2 LASTPIN (2925 1750) $PN 103
J 2
(2915 1760);
DISPLAY 0.617021 (2915 1760);
PAINT ORANGE (2915 1760);
FORCEPROP 2 LASTPIN (2925 1700) $PN 105
J 2
(2915 1710);
DISPLAY 0.617021 (2915 1710);
PAINT ORANGE (2915 1710);
FORCEPROP 2 LASTPIN (2925 1650) $PN 107
J 2
(2915 1660);
DISPLAY 0.617021 (2915 1660);
PAINT ORANGE (2915 1660);
FORCEPROP 2 LASTPIN (2925 1600) $PN 109
J 2
(2915 1610);
DISPLAY 0.617021 (2915 1610);
PAINT ORANGE (2915 1610);
FORCEPROP 2 LASTPIN (2925 1550) $PN 112
J 2
(2915 1560);
DISPLAY 0.617021 (2915 1560);
PAINT ORANGE (2915 1560);
FORCEPROP 2 LASTPIN (2925 1500) $PN 114
J 2
(2915 1510);
DISPLAY 0.617021 (2915 1510);
PAINT ORANGE (2915 1510);
FORCEPROP 2 LASTPIN (2925 1450) $PN 116
J 2
(2915 1460);
DISPLAY 0.617021 (2915 1460);
PAINT ORANGE (2915 1460);
FORCEPROP 2 LASTPIN (2925 1400) $PN 118
J 2
(2915 1410);
DISPLAY 0.617021 (2915 1410);
PAINT ORANGE (2915 1410);
FORCEPROP 2 LASTPIN (2925 1350) $PN 120
J 2
(2915 1360);
DISPLAY 0.617021 (2915 1360);
PAINT ORANGE (2915 1360);
FORCEPROP 2 LASTPIN (2925 1300) $PN 123
J 2
(2915 1310);
DISPLAY 0.617021 (2915 1310);
PAINT ORANGE (2915 1310);
FORCEPROP 2 LASTPIN (2925 1250) $PN 125
J 2
(2915 1260);
DISPLAY 0.617021 (2915 1260);
PAINT ORANGE (2915 1260);
FORCEPROP 2 LASTPIN (2925 1200) $PN 127
J 2
(2915 1210);
DISPLAY 0.617021 (2915 1210);
PAINT ORANGE (2915 1210);
FORCEPROP 2 LASTPIN (2925 1150) $PN 129
J 2
(2915 1160);
DISPLAY 0.617021 (2915 1160);
PAINT ORANGE (2915 1160);
FORCEPROP 2 LASTPIN (2925 1100) $PN 131
J 2
(2915 1110);
DISPLAY 0.617021 (2915 1110);
PAINT ORANGE (2915 1110);
FORCEPROP 2 LASTPIN (2925 1050) $PN 134
J 2
(2915 1060);
DISPLAY 0.617021 (2915 1060);
PAINT ORANGE (2915 1060);
FORCEPROP 2 LASTPIN (2925 1000) $PN 136
J 2
(2915 1010);
DISPLAY 0.617021 (2915 1010);
PAINT ORANGE (2915 1010);
FORCEPROP 2 LASTPIN (2925 950) $PN 138
J 2
(2915 960);
DISPLAY 0.617021 (2915 960);
PAINT ORANGE (2915 960);
FORCEPROP 2 LASTPIN (3925 3250) $PN 147
J 0
(3935 3260);
DISPLAY 0.617021 (3935 3260);
PAINT ORANGE (3935 3260);
FORCEPROP 2 LASTPIN (3925 3200) $PN 149
J 0
(3935 3210);
DISPLAY 0.617021 (3935 3210);
PAINT ORANGE (3935 3210);
FORCEPROP 2 LASTPIN (3925 3150) $PN 151
J 0
(3935 3160);
DISPLAY 0.617021 (3935 3160);
PAINT ORANGE (3935 3160);
FORCEPROP 2 LASTPIN (3925 3100) $PN 154
J 0
(3935 3110);
DISPLAY 0.617021 (3935 3110);
PAINT ORANGE (3935 3110);
FORCEPROP 2 LASTPIN (3925 3050) $PN 156
J 0
(3935 3060);
DISPLAY 0.617021 (3935 3060);
PAINT ORANGE (3935 3060);
FORCEPROP 2 LASTPIN (3925 3000) $PN 158
J 0
(3935 3010);
DISPLAY 0.617021 (3935 3010);
PAINT ORANGE (3935 3010);
FORCEPROP 2 LASTPIN (3925 2950) $PN 160
J 0
(3935 2960);
DISPLAY 0.617021 (3935 2960);
PAINT ORANGE (3935 2960);
FORCEPROP 2 LASTPIN (3925 2900) $PN 162
J 0
(3935 2910);
DISPLAY 0.617021 (3935 2910);
PAINT ORANGE (3935 2910);
FORCEPROP 2 LASTPIN (3925 2850) $PN 165
J 0
(3935 2860);
DISPLAY 0.617021 (3935 2860);
PAINT ORANGE (3935 2860);
FORCEPROP 2 LASTPIN (3925 2800) $PN 167
J 0
(3935 2810);
DISPLAY 0.617021 (3935 2810);
PAINT ORANGE (3935 2810);
FORCEPROP 2 LASTPIN (3925 2750) $PN 169
J 0
(3935 2760);
DISPLAY 0.617021 (3935 2760);
PAINT ORANGE (3935 2760);
FORCEPROP 2 LASTPIN (3925 2700) $PN 171
J 0
(3935 2710);
DISPLAY 0.617021 (3935 2710);
PAINT ORANGE (3935 2710);
FORCEPROP 2 LASTPIN (3925 2650) $PN 173
J 0
(3935 2660);
DISPLAY 0.617021 (3935 2660);
PAINT ORANGE (3935 2660);
FORCEPROP 2 LASTPIN (3925 2600) $PN 176
J 0
(3935 2610);
DISPLAY 0.617021 (3935 2610);
PAINT ORANGE (3935 2610);
FORCEPROP 2 LASTPIN (3925 2550) $PN 178
J 0
(3935 2560);
DISPLAY 0.617021 (3935 2560);
PAINT ORANGE (3935 2560);
FORCEPROP 2 LASTPIN (3925 2500) $PN 180
J 0
(3935 2510);
DISPLAY 0.617021 (3935 2510);
PAINT ORANGE (3935 2510);
FORCEPROP 2 LASTPIN (3925 2450) $PN 182
J 0
(3935 2460);
DISPLAY 0.617021 (3935 2460);
PAINT ORANGE (3935 2460);
FORCEPROP 2 LASTPIN (3925 2400) $PN 184
J 0
(3935 2410);
DISPLAY 0.617021 (3935 2410);
PAINT ORANGE (3935 2410);
FORCEPROP 2 LASTPIN (3925 2350) $PN 187
J 0
(3935 2360);
DISPLAY 0.617021 (3935 2360);
PAINT ORANGE (3935 2360);
FORCEPROP 2 LASTPIN (3925 2300) $PN 189
J 0
(3935 2310);
DISPLAY 0.617021 (3935 2310);
PAINT ORANGE (3935 2310);
FORCEPROP 2 LASTPIN (3925 2250) $PN 191
J 0
(3935 2260);
DISPLAY 0.617021 (3935 2260);
PAINT ORANGE (3935 2260);
FORCEPROP 2 LASTPIN (3925 2200) $PN 193
J 0
(3935 2210);
DISPLAY 0.617021 (3935 2210);
PAINT ORANGE (3935 2210);
FORCEPROP 2 LASTPIN (3925 2150) $PN 195
J 0
(3935 2160);
DISPLAY 0.617021 (3935 2160);
PAINT ORANGE (3935 2160);
FORCEPROP 2 LASTPIN (3925 2100) $PN 198
J 0
(3935 2110);
DISPLAY 0.617021 (3935 2110);
PAINT ORANGE (3935 2110);
FORCEPROP 2 LASTPIN (3925 2050) $PN 200
J 0
(3935 2060);
DISPLAY 0.617021 (3935 2060);
PAINT ORANGE (3935 2060);
FORCEPROP 2 LASTPIN (3925 2000) $PN 202
J 0
(3935 2010);
DISPLAY 0.617021 (3935 2010);
PAINT ORANGE (3935 2010);
FORCEPROP 2 LASTPIN (3925 1950) $PN 239
J 0
(3935 1960);
DISPLAY 0.617021 (3935 1960);
PAINT ORANGE (3935 1960);
FORCEPROP 2 LASTPIN (3925 1900) $PN 241
J 0
(3935 1910);
DISPLAY 0.617021 (3935 1910);
PAINT ORANGE (3935 1910);
FORCEPROP 2 LASTPIN (3925 1850) $PN 243
J 0
(3935 1860);
DISPLAY 0.617021 (3935 1860);
PAINT ORANGE (3935 1860);
FORCEPROP 2 LASTPIN (3925 1800) $PN 246
J 0
(3935 1810);
DISPLAY 0.617021 (3935 1810);
PAINT ORANGE (3935 1810);
FORCEPROP 2 LASTPIN (3925 1750) $PN 248
J 0
(3935 1760);
DISPLAY 0.617021 (3935 1760);
PAINT ORANGE (3935 1760);
FORCEPROP 2 LASTPIN (3925 1700) $PN 250
J 0
(3935 1710);
DISPLAY 0.617021 (3935 1710);
PAINT ORANGE (3935 1710);
FORCEPROP 2 LASTPIN (3925 1650) $PN 252
J 0
(3935 1660);
DISPLAY 0.617021 (3935 1660);
PAINT ORANGE (3935 1660);
FORCEPROP 2 LASTPIN (3925 1600) $PN 254
J 0
(3935 1610);
DISPLAY 0.617021 (3935 1610);
PAINT ORANGE (3935 1610);
FORCEPROP 2 LASTPIN (3925 1550) $PN 257
J 0
(3935 1560);
DISPLAY 0.617021 (3935 1560);
PAINT ORANGE (3935 1560);
FORCEPROP 2 LASTPIN (3925 1500) $PN 259
J 0
(3935 1510);
DISPLAY 0.617021 (3935 1510);
PAINT ORANGE (3935 1510);
FORCEPROP 2 LASTPIN (3925 1450) $PN 261
J 0
(3935 1460);
DISPLAY 0.617021 (3935 1460);
PAINT ORANGE (3935 1460);
FORCEPROP 2 LASTPIN (3925 1400) $PN 263
J 0
(3935 1410);
DISPLAY 0.617021 (3935 1410);
PAINT ORANGE (3935 1410);
FORCEPROP 2 LASTPIN (3925 1350) $PN 265
J 0
(3935 1360);
DISPLAY 0.617021 (3935 1360);
PAINT ORANGE (3935 1360);
FORCEPROP 2 LASTPIN (3925 1300) $PN 268
J 0
(3935 1310);
DISPLAY 0.617021 (3935 1310);
PAINT ORANGE (3935 1310);
FORCEPROP 2 LASTPIN (3925 1250) $PN 270
J 0
(3935 1260);
DISPLAY 0.617021 (3935 1260);
PAINT ORANGE (3935 1260);
FORCEPROP 2 LASTPIN (3925 1200) $PN 272
J 0
(3935 1210);
DISPLAY 0.617021 (3935 1210);
PAINT ORANGE (3935 1210);
FORCEPROP 2 LASTPIN (3925 1150) $PN 274
J 0
(3935 1160);
DISPLAY 0.617021 (3935 1160);
PAINT ORANGE (3935 1160);
FORCEPROP 2 LASTPIN (3925 1100) $PN 276
J 0
(3935 1110);
DISPLAY 0.617021 (3935 1110);
PAINT ORANGE (3935 1110);
FORCEPROP 2 LASTPIN (3925 1050) $PN 279
J 0
(3935 1060);
DISPLAY 0.617021 (3935 1060);
PAINT ORANGE (3935 1060);
FORCEPROP 2 LASTPIN (3925 1000) $PN 281
J 0
(3935 1010);
DISPLAY 0.617021 (3935 1010);
PAINT ORANGE (3935 1010);
FORCEPROP 2 LASTPIN (3925 950) $PN 283
J 0
(3935 960);
DISPLAY 0.617021 (3935 960);
PAINT ORANGE (3935 960);
FORCEPROP 1 LAST PACK_TYPE PIP
J 0
(2975 3550);
PAINT SKYBLUE (2975 3550);
DISPLAY INVISIBLE (2975 3550);
FORCEPROP 2 LAST BOM_COST MEM
J 0
(2975 3550);
PAINT MONO (2975 3550);
DISPLAY INVISIBLE (2975 3550);
FORCEPROP 2 LAST CDS_LIB mstr_sconn
J 0
(3425 2100);
PAINT ORANGE (3425 2100);
DISPLAY INVISIBLE (3425 2100);
FORCEPROP 2 LAST SEC_TYPE PIP
J 0
(2975 3550);
DISPLAY 1.021277 (2975 3550);
PAINT ORANGE (2975 3550);
DISPLAY INVISIBLE (2975 3550);
FORCEPROP 2 LAST SEC 3
J 0
(2975 3550);
DISPLAY 0.680851 (2975 3550);
PAINT MONO (2975 3550);
DISPLAY INVISIBLE (2975 3550);
FORCEPROP 2 LAST CDS_LOCATION J6L2
J 0
(2975 3500);
DISPLAY 0.617021 (2975 3500);
PAINT AQUA (2975 3500);
DISPLAY INVISIBLE (2975 3500);
FORCEPROP 1 LAST PATH I138
J 0
(3425 3450);
PAINT GREEN (3425 3450);
DISPLAY INVISIBLE (3425 3450);
FORCEPROP 2 LAST ROOM DDR4_CH_E
J 0
(2975 3550);
PAINT MONO (2975 3550);
DISPLAY INVISIBLE (2975 3550);
FORCEADD OFFPAGE..1
(-2275 1800);
FORCEPROP 2 LAST $XR0 27 
J 0
(-2526 1800);
DISPLAY 0.638298 (-2526 1800);
PAINT MONO (-2526 1800);
FORCEPROP 2 LAST $XR1 51 
J 0
(-2616 1800);
DISPLAY 0.638298 (-2616 1800);
PAINT MONO (-2616 1800);
FORCEPROP 2 LAST CDS_LIB mstr_standard
J 0
(-2275 1800);
DISPLAY 0.787234 (-2275 1800);
PAINT MONO (-2275 1800);
DISPLAY INVISIBLE (-2275 1800);
FORCEPROP 1 LAST OFFPAGE TRUE
J 0
(-1950 1675);
DISPLAY 0.936170 (-1950 1675);
PAINT GREEN (-1950 1675);
DISPLAY INVISIBLE (-1950 1675);
FORCEPROP 1 LAST COMMENT_BODY TRUE
J 0
(-2150 1700);
DISPLAY 0.936170 (-2150 1700);
PAINT GREEN (-2150 1700);
DISPLAY INVISIBLE (-2150 1700);
FORCEPROP 2 LAST PATH I14
J 0
(-2550 1850);
DISPLAY 1.021277 (-2550 1850);
PAINT ORANGE (-2550 1850);
DISPLAY INVISIBLE (-2550 1850);
FORCEADD TAP..6
R 2
(2325 3050);
FORCEPROP 3 LASTPIN (2275 3050) SIG_NAME M_E_DQS_DP<0>
J 0
(2285 3060);
DISPLAY 0.659574 (2285 3060);
PAINT MONO (2285 3060);
DISPLAY INVISIBLE (2285 3060);
FORCEPROP 1 LASTPIN (2275 3050) BN 0
J 2
(2325 3060);
DISPLAY 0.617021 (2325 3060);
PAINT PINK (2325 3060);
FORCEPROP 2 LAST CDS_LIB mstr_standard
J 0
(2325 3050);
DISPLAY 0.787234 (2325 3050);
PAINT MONO (2325 3050);
DISPLAY INVISIBLE (2325 3050);
FORCEPROP 1 LAST BODY_TYPE PLUMBING
J 2
(2325 3000);
DISPLAY 1.234043 (2325 3000);
PAINT GREEN (2325 3000);
DISPLAY INVISIBLE (2325 3000);
FORCEPROP 1 LAST HDL_TAP TRUE
J 2
(2000 2925);
DISPLAY 1.234043 (2000 2925);
PAINT GREEN (2000 2925);
DISPLAY INVISIBLE (2000 2925);
FORCEPROP 1 LAST PATH I142
J 2
(2327 3050);
DISPLAY 0.872340 (2327 3050);
PAINT GREEN (2327 3050);
DISPLAY INVISIBLE (2327 3050);
FORCEADD TAP..6
R 2
(2325 3150);
FORCEPROP 3 LASTPIN (2275 3150) SIG_NAME M_E_DQS_DP<1>
J 0
(2285 3160);
DISPLAY 0.659574 (2285 3160);
PAINT MONO (2285 3160);
DISPLAY INVISIBLE (2285 3160);
FORCEPROP 1 LASTPIN (2275 3150) BN 1
J 2
(2325 3160);
DISPLAY 0.617021 (2325 3160);
PAINT PINK (2325 3160);
FORCEPROP 2 LAST CDS_LIB mstr_standard
J 0
(2325 3150);
DISPLAY 0.787234 (2325 3150);
PAINT MONO (2325 3150);
DISPLAY INVISIBLE (2325 3150);
FORCEPROP 1 LAST BODY_TYPE PLUMBING
J 2
(2325 3100);
DISPLAY 1.234043 (2325 3100);
PAINT GREEN (2325 3100);
DISPLAY INVISIBLE (2325 3100);
FORCEPROP 1 LAST HDL_TAP TRUE
J 2
(2000 3025);
DISPLAY 1.234043 (2000 3025);
PAINT GREEN (2000 3025);
DISPLAY INVISIBLE (2000 3025);
FORCEPROP 1 LAST PATH I143
J 2
(2327 3150);
DISPLAY 0.872340 (2327 3150);
PAINT GREEN (2327 3150);
DISPLAY INVISIBLE (2327 3150);
FORCEADD TAP..6
R 2
(2525 3000);
FORCEPROP 3 LASTPIN (2475 3000) SIG_NAME M_E_DQS_DN<0>
J 0
(2485 3010);
DISPLAY 0.659574 (2485 3010);
PAINT MONO (2485 3010);
DISPLAY INVISIBLE (2485 3010);
FORCEPROP 1 LASTPIN (2475 3000) BN 0
J 2
(2525 3010);
DISPLAY 0.617021 (2525 3010);
PAINT PINK (2525 3010);
FORCEPROP 2 LAST CDS_LIB mstr_standard
J 0
(2525 3000);
DISPLAY 0.787234 (2525 3000);
PAINT MONO (2525 3000);
DISPLAY INVISIBLE (2525 3000);
FORCEPROP 1 LAST BODY_TYPE PLUMBING
J 2
(2525 2950);
DISPLAY 1.234043 (2525 2950);
PAINT GREEN (2525 2950);
DISPLAY INVISIBLE (2525 2950);
FORCEPROP 1 LAST HDL_TAP TRUE
J 2
(2200 2875);
DISPLAY 1.234043 (2200 2875);
PAINT GREEN (2200 2875);
DISPLAY INVISIBLE (2200 2875);
FORCEPROP 1 LAST PATH I144
J 2
(2527 3000);
DISPLAY 0.872340 (2527 3000);
PAINT GREEN (2527 3000);
DISPLAY INVISIBLE (2527 3000);
FORCEADD TAP..6
R 2
(2525 3100);
FORCEPROP 3 LASTPIN (2475 3100) SIG_NAME M_E_DQS_DN<1>
J 0
(2485 3110);
DISPLAY 0.659574 (2485 3110);
PAINT MONO (2485 3110);
DISPLAY INVISIBLE (2485 3110);
FORCEPROP 1 LASTPIN (2475 3100) BN 1
J 2
(2525 3110);
DISPLAY 0.617021 (2525 3110);
PAINT PINK (2525 3110);
FORCEPROP 2 LAST CDS_LIB mstr_standard
J 0
(2525 3100);
DISPLAY 0.787234 (2525 3100);
PAINT MONO (2525 3100);
DISPLAY INVISIBLE (2525 3100);
FORCEPROP 1 LAST BODY_TYPE PLUMBING
J 2
(2525 3050);
DISPLAY 1.234043 (2525 3050);
PAINT GREEN (2525 3050);
DISPLAY INVISIBLE (2525 3050);
FORCEPROP 1 LAST HDL_TAP TRUE
J 2
(2200 2975);
DISPLAY 1.234043 (2200 2975);
PAINT GREEN (2200 2975);
DISPLAY INVISIBLE (2200 2975);
FORCEPROP 1 LAST PATH I145
J 2
(2527 3100);
DISPLAY 0.872340 (2527 3100);
PAINT GREEN (2527 3100);
DISPLAY INVISIBLE (2527 3100);
FORCEADD TAP..6
R 2
(2325 3250);
FORCEPROP 3 LASTPIN (2275 3250) SIG_NAME M_E_DQS_DP<2>
J 0
(2285 3260);
DISPLAY 0.659574 (2285 3260);
PAINT MONO (2285 3260);
DISPLAY INVISIBLE (2285 3260);
FORCEPROP 1 LASTPIN (2275 3250) BN 2
J 2
(2325 3260);
DISPLAY 0.617021 (2325 3260);
PAINT PINK (2325 3260);
FORCEPROP 2 LAST CDS_LIB mstr_standard
J 0
(2325 3250);
DISPLAY 0.787234 (2325 3250);
PAINT MONO (2325 3250);
DISPLAY INVISIBLE (2325 3250);
FORCEPROP 1 LAST BODY_TYPE PLUMBING
J 2
(2325 3200);
DISPLAY 1.234043 (2325 3200);
PAINT GREEN (2325 3200);
DISPLAY INVISIBLE (2325 3200);
FORCEPROP 1 LAST HDL_TAP TRUE
J 2
(2000 3125);
DISPLAY 1.234043 (2000 3125);
PAINT GREEN (2000 3125);
DISPLAY INVISIBLE (2000 3125);
FORCEPROP 1 LAST PATH I146
J 2
(2327 3250);
DISPLAY 0.872340 (2327 3250);
PAINT GREEN (2327 3250);
DISPLAY INVISIBLE (2327 3250);
FORCEADD TAP..6
R 2
(2325 3350);
FORCEPROP 3 LASTPIN (2275 3350) SIG_NAME M_E_DQS_DP<3>
J 0
(2285 3360);
DISPLAY 0.659574 (2285 3360);
PAINT MONO (2285 3360);
DISPLAY INVISIBLE (2285 3360);
FORCEPROP 1 LASTPIN (2275 3350) BN 3
J 2
(2325 3360);
DISPLAY 0.617021 (2325 3360);
PAINT PINK (2325 3360);
FORCEPROP 2 LAST CDS_LIB mstr_standard
J 0
(2325 3350);
DISPLAY 0.787234 (2325 3350);
PAINT MONO (2325 3350);
DISPLAY INVISIBLE (2325 3350);
FORCEPROP 1 LAST BODY_TYPE PLUMBING
J 2
(2325 3300);
DISPLAY 1.234043 (2325 3300);
PAINT GREEN (2325 3300);
DISPLAY INVISIBLE (2325 3300);
FORCEPROP 1 LAST HDL_TAP TRUE
J 2
(2000 3225);
DISPLAY 1.234043 (2000 3225);
PAINT GREEN (2000 3225);
DISPLAY INVISIBLE (2000 3225);
FORCEPROP 1 LAST PATH I147
J 2
(2327 3350);
DISPLAY 0.872340 (2327 3350);
PAINT GREEN (2327 3350);
DISPLAY INVISIBLE (2327 3350);
FORCEADD TAP..6
R 2
(2325 3450);
FORCEPROP 3 LASTPIN (2275 3450) SIG_NAME M_E_DQS_DP<4>
J 0
(2285 3460);
DISPLAY 0.659574 (2285 3460);
PAINT MONO (2285 3460);
DISPLAY INVISIBLE (2285 3460);
FORCEPROP 1 LASTPIN (2275 3450) BN 4
J 2
(2325 3460);
DISPLAY 0.617021 (2325 3460);
PAINT PINK (2325 3460);
FORCEPROP 2 LAST CDS_LIB mstr_standard
J 0
(2325 3450);
DISPLAY 0.787234 (2325 3450);
PAINT MONO (2325 3450);
DISPLAY INVISIBLE (2325 3450);
FORCEPROP 1 LAST BODY_TYPE PLUMBING
J 2
(2325 3400);
DISPLAY 1.234043 (2325 3400);
PAINT GREEN (2325 3400);
DISPLAY INVISIBLE (2325 3400);
FORCEPROP 1 LAST HDL_TAP TRUE
J 2
(2000 3325);
DISPLAY 1.234043 (2000 3325);
PAINT GREEN (2000 3325);
DISPLAY INVISIBLE (2000 3325);
FORCEPROP 1 LAST PATH I148
J 2
(2327 3450);
DISPLAY 0.872340 (2327 3450);
PAINT GREEN (2327 3450);
DISPLAY INVISIBLE (2327 3450);
FORCEADD TAP..6
R 2
(2325 3550);
FORCEPROP 3 LASTPIN (2275 3550) SIG_NAME M_E_DQS_DP<5>
J 0
(2285 3560);
DISPLAY 0.659574 (2285 3560);
PAINT MONO (2285 3560);
DISPLAY INVISIBLE (2285 3560);
FORCEPROP 1 LASTPIN (2275 3550) BN 5
J 2
(2325 3560);
DISPLAY 0.617021 (2325 3560);
PAINT PINK (2325 3560);
FORCEPROP 2 LAST CDS_LIB mstr_standard
J 0
(2325 3550);
DISPLAY 0.787234 (2325 3550);
PAINT MONO (2325 3550);
DISPLAY INVISIBLE (2325 3550);
FORCEPROP 1 LAST BODY_TYPE PLUMBING
J 2
(2325 3500);
DISPLAY 1.234043 (2325 3500);
PAINT GREEN (2325 3500);
DISPLAY INVISIBLE (2325 3500);
FORCEPROP 1 LAST HDL_TAP TRUE
J 2
(2000 3425);
DISPLAY 1.234043 (2000 3425);
PAINT GREEN (2000 3425);
DISPLAY INVISIBLE (2000 3425);
FORCEPROP 1 LAST PATH I149
J 2
(2327 3550);
DISPLAY 0.872340 (2327 3550);
PAINT GREEN (2327 3550);
DISPLAY INVISIBLE (2327 3550);
FORCEADD OFFPAGE..1
(-2275 2400);
FORCEPROP 2 LAST $XR0 21 
J 0
(-2496 2400);
DISPLAY 0.638298 (-2496 2400);
PAINT MONO (-2496 2400);
FORCEPROP 2 LAST $XR1 49 
J 0
(-2586 2400);
DISPLAY 0.638298 (-2586 2400);
PAINT MONO (-2586 2400);
FORCEPROP 2 LAST $XR2 50 
J 0
(-2676 2400);
DISPLAY 0.638298 (-2676 2400);
PAINT MONO (-2676 2400);
FORCEPROP 2 LAST $XR3 51 
J 0
(-2766 2400);
DISPLAY 0.638298 (-2766 2400);
PAINT MONO (-2766 2400);
FORCEPROP 2 LAST $XR4 53 
J 0
(-2856 2400);
DISPLAY 0.638298 (-2856 2400);
PAINT MONO (-2856 2400);
FORCEPROP 2 LAST $XR5 54 
J 0
(-2946 2400);
DISPLAY 0.638298 (-2946 2400);
PAINT MONO (-2946 2400);
FORCEPROP 2 LAST CDS_LIB mstr_standard
J 0
(-2275 2400);
DISPLAY 0.787234 (-2275 2400);
PAINT MONO (-2275 2400);
DISPLAY INVISIBLE (-2275 2400);
FORCEPROP 1 LAST OFFPAGE TRUE
J 0
(-1950 2275);
DISPLAY 0.936170 (-1950 2275);
PAINT GREEN (-1950 2275);
DISPLAY INVISIBLE (-1950 2275);
FORCEPROP 1 LAST COMMENT_BODY TRUE
J 0
(-2150 2300);
DISPLAY 0.936170 (-2150 2300);
PAINT GREEN (-2150 2300);
DISPLAY INVISIBLE (-2150 2300);
FORCEPROP 2 LAST PATH I15
J 0
(-2450 2450);
DISPLAY 1.021277 (-2450 2450);
PAINT ORANGE (-2450 2450);
DISPLAY INVISIBLE (-2450 2450);
FORCEADD TAP..6
R 2
(2325 3650);
FORCEPROP 3 LASTPIN (2275 3650) SIG_NAME M_E_DQS_DP<6>
J 0
(2285 3660);
DISPLAY 0.659574 (2285 3660);
PAINT MONO (2285 3660);
DISPLAY INVISIBLE (2285 3660);
FORCEPROP 1 LASTPIN (2275 3650) BN 6
J 2
(2325 3660);
DISPLAY 0.617021 (2325 3660);
PAINT PINK (2325 3660);
FORCEPROP 2 LAST CDS_LIB mstr_standard
J 0
(2325 3650);
DISPLAY 0.787234 (2325 3650);
PAINT MONO (2325 3650);
DISPLAY INVISIBLE (2325 3650);
FORCEPROP 1 LAST BODY_TYPE PLUMBING
J 2
(2325 3600);
DISPLAY 1.234043 (2325 3600);
PAINT GREEN (2325 3600);
DISPLAY INVISIBLE (2325 3600);
FORCEPROP 1 LAST HDL_TAP TRUE
J 2
(2000 3525);
DISPLAY 1.234043 (2000 3525);
PAINT GREEN (2000 3525);
DISPLAY INVISIBLE (2000 3525);
FORCEPROP 1 LAST PATH I150
J 2
(2327 3650);
DISPLAY 0.872340 (2327 3650);
PAINT GREEN (2327 3650);
DISPLAY INVISIBLE (2327 3650);
FORCEADD TAP..6
R 2
(2525 3400);
FORCEPROP 3 LASTPIN (2475 3400) SIG_NAME M_E_DQS_DN<4>
J 0
(2485 3410);
DISPLAY 0.659574 (2485 3410);
PAINT MONO (2485 3410);
DISPLAY INVISIBLE (2485 3410);
FORCEPROP 1 LASTPIN (2475 3400) BN 4
J 2
(2525 3410);
DISPLAY 0.617021 (2525 3410);
PAINT PINK (2525 3410);
FORCEPROP 2 LAST CDS_LIB mstr_standard
J 0
(2525 3400);
DISPLAY 0.787234 (2525 3400);
PAINT MONO (2525 3400);
DISPLAY INVISIBLE (2525 3400);
FORCEPROP 1 LAST BODY_TYPE PLUMBING
J 2
(2525 3350);
DISPLAY 1.234043 (2525 3350);
PAINT GREEN (2525 3350);
DISPLAY INVISIBLE (2525 3350);
FORCEPROP 1 LAST HDL_TAP TRUE
J 2
(2200 3275);
DISPLAY 1.234043 (2200 3275);
PAINT GREEN (2200 3275);
DISPLAY INVISIBLE (2200 3275);
FORCEPROP 1 LAST PATH I151
J 2
(2527 3400);
DISPLAY 0.872340 (2527 3400);
PAINT GREEN (2527 3400);
DISPLAY INVISIBLE (2527 3400);
FORCEADD TAP..6
R 2
(2525 3200);
FORCEPROP 3 LASTPIN (2475 3200) SIG_NAME M_E_DQS_DN<2>
J 0
(2485 3210);
DISPLAY 0.659574 (2485 3210);
PAINT MONO (2485 3210);
DISPLAY INVISIBLE (2485 3210);
FORCEPROP 1 LASTPIN (2475 3200) BN 2
J 2
(2525 3210);
DISPLAY 0.617021 (2525 3210);
PAINT PINK (2525 3210);
FORCEPROP 2 LAST CDS_LIB mstr_standard
J 0
(2525 3200);
DISPLAY 0.787234 (2525 3200);
PAINT MONO (2525 3200);
DISPLAY INVISIBLE (2525 3200);
FORCEPROP 1 LAST BODY_TYPE PLUMBING
J 2
(2525 3150);
DISPLAY 1.234043 (2525 3150);
PAINT GREEN (2525 3150);
DISPLAY INVISIBLE (2525 3150);
FORCEPROP 1 LAST HDL_TAP TRUE
J 2
(2200 3075);
DISPLAY 1.234043 (2200 3075);
PAINT GREEN (2200 3075);
DISPLAY INVISIBLE (2200 3075);
FORCEPROP 1 LAST PATH I152
J 2
(2527 3200);
DISPLAY 0.872340 (2527 3200);
PAINT GREEN (2527 3200);
DISPLAY INVISIBLE (2527 3200);
FORCEADD TAP..6
R 2
(2525 3300);
FORCEPROP 3 LASTPIN (2475 3300) SIG_NAME M_E_DQS_DN<3>
J 0
(2485 3310);
DISPLAY 0.659574 (2485 3310);
PAINT MONO (2485 3310);
DISPLAY INVISIBLE (2485 3310);
FORCEPROP 1 LASTPIN (2475 3300) BN 3
J 2
(2525 3310);
DISPLAY 0.617021 (2525 3310);
PAINT PINK (2525 3310);
FORCEPROP 2 LAST CDS_LIB mstr_standard
J 0
(2525 3300);
DISPLAY 0.787234 (2525 3300);
PAINT MONO (2525 3300);
DISPLAY INVISIBLE (2525 3300);
FORCEPROP 1 LAST BODY_TYPE PLUMBING
J 2
(2525 3250);
DISPLAY 1.234043 (2525 3250);
PAINT GREEN (2525 3250);
DISPLAY INVISIBLE (2525 3250);
FORCEPROP 1 LAST HDL_TAP TRUE
J 2
(2200 3175);
DISPLAY 1.234043 (2200 3175);
PAINT GREEN (2200 3175);
DISPLAY INVISIBLE (2200 3175);
FORCEPROP 1 LAST PATH I153
J 2
(2527 3300);
DISPLAY 0.872340 (2527 3300);
PAINT GREEN (2527 3300);
DISPLAY INVISIBLE (2527 3300);
FORCEADD TAP..6
R 2
(2525 3600);
FORCEPROP 3 LASTPIN (2475 3600) SIG_NAME M_E_DQS_DN<6>
J 0
(2485 3610);
DISPLAY 0.659574 (2485 3610);
PAINT MONO (2485 3610);
DISPLAY INVISIBLE (2485 3610);
FORCEPROP 1 LASTPIN (2475 3600) BN 6
J 2
(2525 3610);
DISPLAY 0.617021 (2525 3610);
PAINT PINK (2525 3610);
FORCEPROP 2 LAST CDS_LIB mstr_standard
J 0
(2525 3600);
DISPLAY 0.787234 (2525 3600);
PAINT MONO (2525 3600);
DISPLAY INVISIBLE (2525 3600);
FORCEPROP 1 LAST BODY_TYPE PLUMBING
J 2
(2525 3550);
DISPLAY 1.234043 (2525 3550);
PAINT GREEN (2525 3550);
DISPLAY INVISIBLE (2525 3550);
FORCEPROP 1 LAST HDL_TAP TRUE
J 2
(2200 3475);
DISPLAY 1.234043 (2200 3475);
PAINT GREEN (2200 3475);
DISPLAY INVISIBLE (2200 3475);
FORCEPROP 1 LAST PATH I154
J 2
(2527 3600);
DISPLAY 0.872340 (2527 3600);
PAINT GREEN (2527 3600);
DISPLAY INVISIBLE (2527 3600);
FORCEADD TAP..6
R 2
(2525 3500);
FORCEPROP 3 LASTPIN (2475 3500) SIG_NAME M_E_DQS_DN<5>
J 0
(2485 3510);
DISPLAY 0.659574 (2485 3510);
PAINT MONO (2485 3510);
DISPLAY INVISIBLE (2485 3510);
FORCEPROP 1 LASTPIN (2475 3500) BN 5
J 2
(2525 3510);
DISPLAY 0.617021 (2525 3510);
PAINT PINK (2525 3510);
FORCEPROP 2 LAST CDS_LIB mstr_standard
J 0
(2525 3500);
DISPLAY 0.787234 (2525 3500);
PAINT MONO (2525 3500);
DISPLAY INVISIBLE (2525 3500);
FORCEPROP 1 LAST BODY_TYPE PLUMBING
J 2
(2525 3450);
DISPLAY 1.234043 (2525 3450);
PAINT GREEN (2525 3450);
DISPLAY INVISIBLE (2525 3450);
FORCEPROP 1 LAST HDL_TAP TRUE
J 2
(2200 3375);
DISPLAY 1.234043 (2200 3375);
PAINT GREEN (2200 3375);
DISPLAY INVISIBLE (2200 3375);
FORCEPROP 1 LAST PATH I155
J 2
(2527 3500);
DISPLAY 0.872340 (2527 3500);
PAINT GREEN (2527 3500);
DISPLAY INVISIBLE (2527 3500);
FORCEADD GND..1
R 2
(4125 800);
FORCEPROP 3 LASTPIN (4125 850) SIG_NAME GND\g
J 0
(4135 860);
DISPLAY 0.659574 (4135 860);
PAINT MONO (4135 860);
DISPLAY INVISIBLE (4135 860);
FORCEPROP 1 LAST VOLTAGE 0
J 0
(4125 800);
PAINT SKYBLUE (4125 800);
DISPLAY INVISIBLE (4125 800);
FORCEPROP 2 LAST CDS_LIB mstr_symbols
J 0
(4125 800);
DISPLAY 0.787234 (4125 800);
PAINT MONO (4125 800);
DISPLAY INVISIBLE (4125 800);
FORCEPROP 1 LAST SIZE 1B
J 2
(4050 750);
DISPLAY 1.170213 (4050 750);
PAINT GREEN (4050 750);
DISPLAY INVISIBLE (4050 750);
FORCEPROP 1 LAST BODY_TYPE PLUMBING
J 2
(4170 757);
DISPLAY 0.340426 (4170 757);
PAINT GREEN (4170 757);
DISPLAY INVISIBLE (4170 757);
FORCEPROP 1 LAST PATH I156
J 2
(4050 800);
DISPLAY 0.872340 (4050 800);
PAINT AQUA (4050 800);
DISPLAY INVISIBLE (4050 800);
FORCEPROP 1 LAST HDL_POWER GND
J 2
(4125 950);
DISPLAY 0.553191 (4125 950);
PAINT GREEN (4125 950);
DISPLAY INVISIBLE (4125 950);
FORCEADD TAP..6
R 2
(2325 3750);
FORCEPROP 3 LASTPIN (2275 3750) SIG_NAME M_E_DQS_DP<7>
J 0
(2285 3760);
DISPLAY 0.659574 (2285 3760);
PAINT MONO (2285 3760);
DISPLAY INVISIBLE (2285 3760);
FORCEPROP 1 LASTPIN (2275 3750) BN 7
J 2
(2325 3760);
DISPLAY 0.617021 (2325 3760);
PAINT PINK (2325 3760);
FORCEPROP 2 LAST CDS_LIB mstr_standard
J 0
(2325 3750);
DISPLAY 0.787234 (2325 3750);
PAINT MONO (2325 3750);
DISPLAY INVISIBLE (2325 3750);
FORCEPROP 1 LAST BODY_TYPE PLUMBING
J 2
(2325 3700);
DISPLAY 1.234043 (2325 3700);
PAINT GREEN (2325 3700);
DISPLAY INVISIBLE (2325 3700);
FORCEPROP 1 LAST HDL_TAP TRUE
J 2
(2000 3625);
DISPLAY 1.234043 (2000 3625);
PAINT GREEN (2000 3625);
DISPLAY INVISIBLE (2000 3625);
FORCEPROP 1 LAST PATH I157
J 2
(2327 3750);
DISPLAY 0.872340 (2327 3750);
PAINT GREEN (2327 3750);
DISPLAY INVISIBLE (2327 3750);
FORCEADD TAP..6
R 2
(2325 3950);
FORCEPROP 3 LASTPIN (2275 3950) SIG_NAME M_E_DQS_DP<9>
J 0
(2285 3960);
DISPLAY 0.659574 (2285 3960);
PAINT MONO (2285 3960);
DISPLAY INVISIBLE (2285 3960);
FORCEPROP 1 LASTPIN (2275 3950) BN 9
J 2
(2325 3960);
DISPLAY 0.617021 (2325 3960);
PAINT PINK (2325 3960);
FORCEPROP 2 LAST CDS_LIB mstr_standard
J 0
(2325 3950);
DISPLAY 0.787234 (2325 3950);
PAINT MONO (2325 3950);
DISPLAY INVISIBLE (2325 3950);
FORCEPROP 1 LAST BODY_TYPE PLUMBING
J 2
(2325 3900);
DISPLAY 1.234043 (2325 3900);
PAINT GREEN (2325 3900);
DISPLAY INVISIBLE (2325 3900);
FORCEPROP 1 LAST HDL_TAP TRUE
J 2
(2000 3825);
DISPLAY 1.234043 (2000 3825);
PAINT GREEN (2000 3825);
DISPLAY INVISIBLE (2000 3825);
FORCEPROP 1 LAST PATH I158
J 2
(2327 3950);
DISPLAY 0.872340 (2327 3950);
PAINT GREEN (2327 3950);
DISPLAY INVISIBLE (2327 3950);
FORCEADD TAP..6
R 2
(2325 3850);
FORCEPROP 3 LASTPIN (2275 3850) SIG_NAME M_E_DQS_DP<8>
J 0
(2285 3860);
DISPLAY 0.659574 (2285 3860);
PAINT MONO (2285 3860);
DISPLAY INVISIBLE (2285 3860);
FORCEPROP 1 LASTPIN (2275 3850) BN 8
J 2
(2325 3860);
DISPLAY 0.617021 (2325 3860);
PAINT PINK (2325 3860);
FORCEPROP 2 LAST CDS_LIB mstr_standard
J 0
(2325 3850);
DISPLAY 0.787234 (2325 3850);
PAINT MONO (2325 3850);
DISPLAY INVISIBLE (2325 3850);
FORCEPROP 1 LAST BODY_TYPE PLUMBING
J 2
(2325 3800);
DISPLAY 1.234043 (2325 3800);
PAINT GREEN (2325 3800);
DISPLAY INVISIBLE (2325 3800);
FORCEPROP 1 LAST HDL_TAP TRUE
J 2
(2000 3725);
DISPLAY 1.234043 (2000 3725);
PAINT GREEN (2000 3725);
DISPLAY INVISIBLE (2000 3725);
FORCEPROP 1 LAST PATH I159
J 2
(2327 3850);
DISPLAY 0.872340 (2327 3850);
PAINT GREEN (2327 3850);
DISPLAY INVISIBLE (2327 3850);
FORCEADD OFFPAGE..6
(-2275 2500);
FORCEPROP 2 LAST $XR0 27 
J 0
(-2524 2500);
DISPLAY 0.638298 (-2524 2500);
PAINT MONO (-2524 2500);
FORCEPROP 2 LAST $XR1 51 
J 0
(-2614 2500);
DISPLAY 0.638298 (-2614 2500);
PAINT MONO (-2614 2500);
FORCEPROP 2 LAST CDS_LIB mstr_standard
J 0
(-2275 2500);
DISPLAY 0.787234 (-2275 2500);
PAINT MONO (-2275 2500);
DISPLAY INVISIBLE (-2275 2500);
FORCEPROP 1 LAST OFFPAGE TRUE
J 0
(-1950 2375);
DISPLAY 0.936170 (-1950 2375);
PAINT GREEN (-1950 2375);
DISPLAY INVISIBLE (-1950 2375);
FORCEPROP 1 LAST COMMENT_BODY TRUE
J 0
(-2175 2425);
DISPLAY 0.936170 (-2175 2425);
PAINT GREEN (-2175 2425);
DISPLAY INVISIBLE (-2175 2425);
FORCEPROP 2 LAST PATH I16
J 0
(-2550 2550);
DISPLAY 1.021277 (-2550 2550);
PAINT ORANGE (-2550 2550);
DISPLAY INVISIBLE (-2550 2550);
FORCEADD TAP..6
R 2
(2325 4050);
FORCEPROP 3 LASTPIN (2275 4050) SIG_NAME M_E_DQS_DP<10>
J 0
(2285 4060);
DISPLAY 0.659574 (2285 4060);
PAINT MONO (2285 4060);
DISPLAY INVISIBLE (2285 4060);
FORCEPROP 1 LASTPIN (2275 4050) BN 10
J 2
(2325 4060);
DISPLAY 0.617021 (2325 4060);
PAINT PINK (2325 4060);
FORCEPROP 2 LAST CDS_LIB mstr_standard
J 0
(2325 4050);
DISPLAY 0.787234 (2325 4050);
PAINT MONO (2325 4050);
DISPLAY INVISIBLE (2325 4050);
FORCEPROP 1 LAST BODY_TYPE PLUMBING
J 2
(2325 4000);
DISPLAY 1.234043 (2325 4000);
PAINT GREEN (2325 4000);
DISPLAY INVISIBLE (2325 4000);
FORCEPROP 1 LAST HDL_TAP TRUE
J 2
(2000 3925);
DISPLAY 1.234043 (2000 3925);
PAINT GREEN (2000 3925);
DISPLAY INVISIBLE (2000 3925);
FORCEPROP 1 LAST PATH I160
J 2
(2327 4050);
DISPLAY 0.872340 (2327 4050);
PAINT GREEN (2327 4050);
DISPLAY INVISIBLE (2327 4050);
FORCEADD TAP..6
R 2
(2325 4150);
FORCEPROP 3 LASTPIN (2275 4150) SIG_NAME M_E_DQS_DP<11>
J 0
(2285 4160);
DISPLAY 0.659574 (2285 4160);
PAINT MONO (2285 4160);
DISPLAY INVISIBLE (2285 4160);
FORCEPROP 1 LASTPIN (2275 4150) BN 11
J 2
(2325 4160);
DISPLAY 0.617021 (2325 4160);
PAINT PINK (2325 4160);
FORCEPROP 2 LAST CDS_LIB mstr_standard
J 0
(2325 4150);
DISPLAY 0.787234 (2325 4150);
PAINT MONO (2325 4150);
DISPLAY INVISIBLE (2325 4150);
FORCEPROP 1 LAST BODY_TYPE PLUMBING
J 2
(2325 4100);
DISPLAY 1.234043 (2325 4100);
PAINT GREEN (2325 4100);
DISPLAY INVISIBLE (2325 4100);
FORCEPROP 1 LAST HDL_TAP TRUE
J 2
(2000 4025);
DISPLAY 1.234043 (2000 4025);
PAINT GREEN (2000 4025);
DISPLAY INVISIBLE (2000 4025);
FORCEPROP 1 LAST PATH I161
J 2
(2327 4150);
DISPLAY 0.872340 (2327 4150);
PAINT GREEN (2327 4150);
DISPLAY INVISIBLE (2327 4150);
FORCEADD TAP..6
R 2
(2525 3900);
FORCEPROP 3 LASTPIN (2475 3900) SIG_NAME M_E_DQS_DN<9>
J 0
(2485 3910);
DISPLAY 0.659574 (2485 3910);
PAINT MONO (2485 3910);
DISPLAY INVISIBLE (2485 3910);
FORCEPROP 1 LASTPIN (2475 3900) BN 9
J 2
(2525 3910);
DISPLAY 0.617021 (2525 3910);
PAINT PINK (2525 3910);
FORCEPROP 2 LAST CDS_LIB mstr_standard
J 0
(2525 3900);
DISPLAY 0.787234 (2525 3900);
PAINT MONO (2525 3900);
DISPLAY INVISIBLE (2525 3900);
FORCEPROP 1 LAST BODY_TYPE PLUMBING
J 2
(2525 3850);
DISPLAY 1.234043 (2525 3850);
PAINT GREEN (2525 3850);
DISPLAY INVISIBLE (2525 3850);
FORCEPROP 1 LAST HDL_TAP TRUE
J 2
(2200 3775);
DISPLAY 1.234043 (2200 3775);
PAINT GREEN (2200 3775);
DISPLAY INVISIBLE (2200 3775);
FORCEPROP 1 LAST PATH I162
J 2
(2527 3900);
DISPLAY 0.872340 (2527 3900);
PAINT GREEN (2527 3900);
DISPLAY INVISIBLE (2527 3900);
FORCEADD TAP..6
R 2
(2525 3700);
FORCEPROP 3 LASTPIN (2475 3700) SIG_NAME M_E_DQS_DN<7>
J 0
(2485 3710);
DISPLAY 0.659574 (2485 3710);
PAINT MONO (2485 3710);
DISPLAY INVISIBLE (2485 3710);
FORCEPROP 1 LASTPIN (2475 3700) BN 7
J 2
(2525 3710);
DISPLAY 0.617021 (2525 3710);
PAINT PINK (2525 3710);
FORCEPROP 2 LAST CDS_LIB mstr_standard
J 0
(2525 3700);
DISPLAY 0.787234 (2525 3700);
PAINT MONO (2525 3700);
DISPLAY INVISIBLE (2525 3700);
FORCEPROP 1 LAST BODY_TYPE PLUMBING
J 2
(2525 3650);
DISPLAY 1.234043 (2525 3650);
PAINT GREEN (2525 3650);
DISPLAY INVISIBLE (2525 3650);
FORCEPROP 1 LAST HDL_TAP TRUE
J 2
(2200 3575);
DISPLAY 1.234043 (2200 3575);
PAINT GREEN (2200 3575);
DISPLAY INVISIBLE (2200 3575);
FORCEPROP 1 LAST PATH I163
J 2
(2527 3700);
DISPLAY 0.872340 (2527 3700);
PAINT GREEN (2527 3700);
DISPLAY INVISIBLE (2527 3700);
FORCEADD TAP..6
R 2
(2525 3800);
FORCEPROP 3 LASTPIN (2475 3800) SIG_NAME M_E_DQS_DN<8>
J 0
(2485 3810);
DISPLAY 0.659574 (2485 3810);
PAINT MONO (2485 3810);
DISPLAY INVISIBLE (2485 3810);
FORCEPROP 1 LASTPIN (2475 3800) BN 8
J 2
(2525 3810);
DISPLAY 0.617021 (2525 3810);
PAINT PINK (2525 3810);
FORCEPROP 2 LAST CDS_LIB mstr_standard
J 0
(2525 3800);
DISPLAY 0.787234 (2525 3800);
PAINT MONO (2525 3800);
DISPLAY INVISIBLE (2525 3800);
FORCEPROP 1 LAST BODY_TYPE PLUMBING
J 2
(2525 3750);
DISPLAY 1.234043 (2525 3750);
PAINT GREEN (2525 3750);
DISPLAY INVISIBLE (2525 3750);
FORCEPROP 1 LAST HDL_TAP TRUE
J 2
(2200 3675);
DISPLAY 1.234043 (2200 3675);
PAINT GREEN (2200 3675);
DISPLAY INVISIBLE (2200 3675);
FORCEPROP 1 LAST PATH I164
J 2
(2527 3800);
DISPLAY 0.872340 (2527 3800);
PAINT GREEN (2527 3800);
DISPLAY INVISIBLE (2527 3800);
FORCEADD TAP..6
R 2
(2525 4100);
FORCEPROP 3 LASTPIN (2475 4100) SIG_NAME M_E_DQS_DN<11>
J 0
(2485 4110);
DISPLAY 0.659574 (2485 4110);
PAINT MONO (2485 4110);
DISPLAY INVISIBLE (2485 4110);
FORCEPROP 1 LASTPIN (2475 4100) BN 11
J 2
(2525 4110);
DISPLAY 0.617021 (2525 4110);
PAINT PINK (2525 4110);
FORCEPROP 2 LAST CDS_LIB mstr_standard
J 0
(2525 4100);
DISPLAY 0.787234 (2525 4100);
PAINT MONO (2525 4100);
DISPLAY INVISIBLE (2525 4100);
FORCEPROP 1 LAST BODY_TYPE PLUMBING
J 2
(2525 4050);
DISPLAY 1.234043 (2525 4050);
PAINT GREEN (2525 4050);
DISPLAY INVISIBLE (2525 4050);
FORCEPROP 1 LAST HDL_TAP TRUE
J 2
(2200 3975);
DISPLAY 1.234043 (2200 3975);
PAINT GREEN (2200 3975);
DISPLAY INVISIBLE (2200 3975);
FORCEPROP 1 LAST PATH I165
J 2
(2527 4100);
DISPLAY 0.872340 (2527 4100);
PAINT GREEN (2527 4100);
DISPLAY INVISIBLE (2527 4100);
FORCEADD TAP..6
R 2
(2525 4000);
FORCEPROP 3 LASTPIN (2475 4000) SIG_NAME M_E_DQS_DN<10>
J 0
(2485 4010);
DISPLAY 0.659574 (2485 4010);
PAINT MONO (2485 4010);
DISPLAY INVISIBLE (2485 4010);
FORCEPROP 1 LASTPIN (2475 4000) BN 10
J 2
(2525 4010);
DISPLAY 0.617021 (2525 4010);
PAINT PINK (2525 4010);
FORCEPROP 2 LAST CDS_LIB mstr_standard
J 0
(2525 4000);
DISPLAY 0.787234 (2525 4000);
PAINT MONO (2525 4000);
DISPLAY INVISIBLE (2525 4000);
FORCEPROP 1 LAST BODY_TYPE PLUMBING
J 2
(2525 3950);
DISPLAY 1.234043 (2525 3950);
PAINT GREEN (2525 3950);
DISPLAY INVISIBLE (2525 3950);
FORCEPROP 1 LAST HDL_TAP TRUE
J 2
(2200 3875);
DISPLAY 1.234043 (2200 3875);
PAINT GREEN (2200 3875);
DISPLAY INVISIBLE (2200 3875);
FORCEPROP 1 LAST PATH I166
J 2
(2527 4000);
DISPLAY 0.872340 (2527 4000);
PAINT GREEN (2527 4000);
DISPLAY INVISIBLE (2527 4000);
FORCEADD TAP..6
R 2
(2525 4200);
FORCEPROP 3 LASTPIN (2475 4200) SIG_NAME M_E_DQS_DN<12>
J 0
(2485 4210);
DISPLAY 0.659574 (2485 4210);
PAINT MONO (2485 4210);
DISPLAY INVISIBLE (2485 4210);
FORCEPROP 1 LASTPIN (2475 4200) BN 12
J 2
(2525 4210);
DISPLAY 0.617021 (2525 4210);
PAINT PINK (2525 4210);
FORCEPROP 2 LAST CDS_LIB mstr_standard
J 0
(2525 4200);
DISPLAY 0.787234 (2525 4200);
PAINT MONO (2525 4200);
DISPLAY INVISIBLE (2525 4200);
FORCEPROP 1 LAST BODY_TYPE PLUMBING
J 2
(2525 4150);
DISPLAY 1.234043 (2525 4150);
PAINT GREEN (2525 4150);
DISPLAY INVISIBLE (2525 4150);
FORCEPROP 1 LAST HDL_TAP TRUE
J 2
(2200 4075);
DISPLAY 1.234043 (2200 4075);
PAINT GREEN (2200 4075);
DISPLAY INVISIBLE (2200 4075);
FORCEPROP 1 LAST PATH I167
J 2
(2527 4200);
DISPLAY 0.872340 (2527 4200);
PAINT GREEN (2527 4200);
DISPLAY INVISIBLE (2527 4200);
FORCEADD TAP..6
R 2
(2325 4250);
FORCEPROP 3 LASTPIN (2275 4250) SIG_NAME M_E_DQS_DP<12>
J 0
(2285 4260);
DISPLAY 0.659574 (2285 4260);
PAINT MONO (2285 4260);
DISPLAY INVISIBLE (2285 4260);
FORCEPROP 1 LASTPIN (2275 4250) BN 12
J 2
(2325 4260);
DISPLAY 0.617021 (2325 4260);
PAINT PINK (2325 4260);
FORCEPROP 2 LAST CDS_LIB mstr_standard
J 0
(2325 4250);
DISPLAY 0.787234 (2325 4250);
PAINT MONO (2325 4250);
DISPLAY INVISIBLE (2325 4250);
FORCEPROP 1 LAST BODY_TYPE PLUMBING
J 2
(2325 4200);
DISPLAY 1.234043 (2325 4200);
PAINT GREEN (2325 4200);
DISPLAY INVISIBLE (2325 4200);
FORCEPROP 1 LAST HDL_TAP TRUE
J 2
(2000 4125);
DISPLAY 1.234043 (2000 4125);
PAINT GREEN (2000 4125);
DISPLAY INVISIBLE (2000 4125);
FORCEPROP 1 LAST PATH I168
J 2
(2327 4250);
DISPLAY 0.872340 (2327 4250);
PAINT GREEN (2327 4250);
DISPLAY INVISIBLE (2327 4250);
FORCEADD TAP..6
R 2
(2325 4450);
FORCEPROP 3 LASTPIN (2275 4450) SIG_NAME M_E_DQS_DP<14>
J 0
(2285 4460);
DISPLAY 0.659574 (2285 4460);
PAINT MONO (2285 4460);
DISPLAY INVISIBLE (2285 4460);
FORCEPROP 1 LASTPIN (2275 4450) BN 14
J 2
(2325 4460);
DISPLAY 0.617021 (2325 4460);
PAINT PINK (2325 4460);
FORCEPROP 2 LAST CDS_LIB mstr_standard
J 0
(2325 4450);
DISPLAY 0.787234 (2325 4450);
PAINT MONO (2325 4450);
DISPLAY INVISIBLE (2325 4450);
FORCEPROP 1 LAST BODY_TYPE PLUMBING
J 2
(2325 4400);
DISPLAY 1.234043 (2325 4400);
PAINT GREEN (2325 4400);
DISPLAY INVISIBLE (2325 4400);
FORCEPROP 1 LAST HDL_TAP TRUE
J 2
(2000 4325);
DISPLAY 1.234043 (2000 4325);
PAINT GREEN (2000 4325);
DISPLAY INVISIBLE (2000 4325);
FORCEPROP 1 LAST PATH I169
J 2
(2327 4450);
DISPLAY 0.872340 (2327 4450);
PAINT GREEN (2327 4450);
DISPLAY INVISIBLE (2327 4450);
FORCEADD OFFPAGE..1
(-2275 2450);
FORCEPROP 2 LAST $XR0 27 
J 0
(-2526 2450);
DISPLAY 0.638298 (-2526 2450);
PAINT MONO (-2526 2450);
FORCEPROP 2 LAST $XR1 51 
J 0
(-2616 2450);
DISPLAY 0.638298 (-2616 2450);
PAINT MONO (-2616 2450);
FORCEPROP 2 LAST CDS_LIB mstr_standard
J 0
(-2275 2450);
DISPLAY 0.787234 (-2275 2450);
PAINT MONO (-2275 2450);
DISPLAY INVISIBLE (-2275 2450);
FORCEPROP 1 LAST OFFPAGE TRUE
J 0
(-1950 2325);
DISPLAY 0.936170 (-1950 2325);
PAINT GREEN (-1950 2325);
DISPLAY INVISIBLE (-1950 2325);
FORCEPROP 1 LAST COMMENT_BODY TRUE
J 0
(-2150 2350);
DISPLAY 0.936170 (-2150 2350);
PAINT GREEN (-2150 2350);
DISPLAY INVISIBLE (-2150 2350);
FORCEPROP 2 LAST PATH I17
J 0
(-2550 2500);
DISPLAY 1.021277 (-2550 2500);
PAINT ORANGE (-2550 2500);
DISPLAY INVISIBLE (-2550 2500);
FORCEADD TAP..6
R 2
(2325 4350);
FORCEPROP 3 LASTPIN (2275 4350) SIG_NAME M_E_DQS_DP<13>
J 0
(2285 4360);
DISPLAY 0.659574 (2285 4360);
PAINT MONO (2285 4360);
DISPLAY INVISIBLE (2285 4360);
FORCEPROP 1 LASTPIN (2275 4350) BN 13
J 2
(2325 4360);
DISPLAY 0.617021 (2325 4360);
PAINT PINK (2325 4360);
FORCEPROP 2 LAST CDS_LIB mstr_standard
J 0
(2325 4350);
DISPLAY 0.787234 (2325 4350);
PAINT MONO (2325 4350);
DISPLAY INVISIBLE (2325 4350);
FORCEPROP 1 LAST BODY_TYPE PLUMBING
J 2
(2325 4300);
DISPLAY 1.234043 (2325 4300);
PAINT GREEN (2325 4300);
DISPLAY INVISIBLE (2325 4300);
FORCEPROP 1 LAST HDL_TAP TRUE
J 2
(2000 4225);
DISPLAY 1.234043 (2000 4225);
PAINT GREEN (2000 4225);
DISPLAY INVISIBLE (2000 4225);
FORCEPROP 1 LAST PATH I170
J 2
(2327 4350);
DISPLAY 0.872340 (2327 4350);
PAINT GREEN (2327 4350);
DISPLAY INVISIBLE (2327 4350);
FORCEADD TAP..6
R 2
(2325 4550);
FORCEPROP 3 LASTPIN (2275 4550) SIG_NAME M_E_DQS_DP<15>
J 0
(2285 4560);
DISPLAY 0.659574 (2285 4560);
PAINT MONO (2285 4560);
DISPLAY INVISIBLE (2285 4560);
FORCEPROP 1 LASTPIN (2275 4550) BN 15
J 2
(2325 4560);
DISPLAY 0.617021 (2325 4560);
PAINT PINK (2325 4560);
FORCEPROP 2 LAST CDS_LIB mstr_standard
J 0
(2325 4550);
DISPLAY 0.787234 (2325 4550);
PAINT MONO (2325 4550);
DISPLAY INVISIBLE (2325 4550);
FORCEPROP 1 LAST BODY_TYPE PLUMBING
J 2
(2325 4500);
DISPLAY 1.234043 (2325 4500);
PAINT GREEN (2325 4500);
DISPLAY INVISIBLE (2325 4500);
FORCEPROP 1 LAST HDL_TAP TRUE
J 2
(2000 4425);
DISPLAY 1.234043 (2000 4425);
PAINT GREEN (2000 4425);
DISPLAY INVISIBLE (2000 4425);
FORCEPROP 1 LAST PATH I171
J 2
(2327 4550);
DISPLAY 0.872340 (2327 4550);
PAINT GREEN (2327 4550);
DISPLAY INVISIBLE (2327 4550);
FORCEADD TAP..6
R 2
(2325 4650);
FORCEPROP 3 LASTPIN (2275 4650) SIG_NAME M_E_DQS_DP<16>
J 0
(2285 4660);
DISPLAY 0.659574 (2285 4660);
PAINT MONO (2285 4660);
DISPLAY INVISIBLE (2285 4660);
FORCEPROP 1 LASTPIN (2275 4650) BN 16
J 2
(2325 4660);
DISPLAY 0.617021 (2325 4660);
PAINT PINK (2325 4660);
FORCEPROP 2 LAST CDS_LIB mstr_standard
J 0
(2325 4650);
DISPLAY 0.787234 (2325 4650);
PAINT MONO (2325 4650);
DISPLAY INVISIBLE (2325 4650);
FORCEPROP 1 LAST BODY_TYPE PLUMBING
J 2
(2325 4600);
DISPLAY 1.234043 (2325 4600);
PAINT GREEN (2325 4600);
DISPLAY INVISIBLE (2325 4600);
FORCEPROP 1 LAST HDL_TAP TRUE
J 2
(2000 4525);
DISPLAY 1.234043 (2000 4525);
PAINT GREEN (2000 4525);
DISPLAY INVISIBLE (2000 4525);
FORCEPROP 1 LAST PATH I172
J 2
(2327 4650);
DISPLAY 0.872340 (2327 4650);
PAINT GREEN (2327 4650);
DISPLAY INVISIBLE (2327 4650);
FORCEADD TAP..6
R 2
(2525 4400);
FORCEPROP 3 LASTPIN (2475 4400) SIG_NAME M_E_DQS_DN<14>
J 0
(2485 4410);
DISPLAY 0.659574 (2485 4410);
PAINT MONO (2485 4410);
DISPLAY INVISIBLE (2485 4410);
FORCEPROP 1 LASTPIN (2475 4400) BN 14
J 2
(2525 4410);
DISPLAY 0.617021 (2525 4410);
PAINT PINK (2525 4410);
FORCEPROP 2 LAST CDS_LIB mstr_standard
J 0
(2525 4400);
DISPLAY 0.787234 (2525 4400);
PAINT MONO (2525 4400);
DISPLAY INVISIBLE (2525 4400);
FORCEPROP 1 LAST BODY_TYPE PLUMBING
J 2
(2525 4350);
DISPLAY 1.234043 (2525 4350);
PAINT GREEN (2525 4350);
DISPLAY INVISIBLE (2525 4350);
FORCEPROP 1 LAST HDL_TAP TRUE
J 2
(2200 4275);
DISPLAY 1.234043 (2200 4275);
PAINT GREEN (2200 4275);
DISPLAY INVISIBLE (2200 4275);
FORCEPROP 1 LAST PATH I173
J 2
(2527 4400);
DISPLAY 0.872340 (2527 4400);
PAINT GREEN (2527 4400);
DISPLAY INVISIBLE (2527 4400);
FORCEADD TAP..6
R 2
(2525 4300);
FORCEPROP 3 LASTPIN (2475 4300) SIG_NAME M_E_DQS_DN<13>
J 0
(2485 4310);
DISPLAY 0.659574 (2485 4310);
PAINT MONO (2485 4310);
DISPLAY INVISIBLE (2485 4310);
FORCEPROP 1 LASTPIN (2475 4300) BN 13
J 2
(2525 4310);
DISPLAY 0.617021 (2525 4310);
PAINT PINK (2525 4310);
FORCEPROP 2 LAST CDS_LIB mstr_standard
J 0
(2525 4300);
DISPLAY 0.787234 (2525 4300);
PAINT MONO (2525 4300);
DISPLAY INVISIBLE (2525 4300);
FORCEPROP 1 LAST BODY_TYPE PLUMBING
J 2
(2525 4250);
DISPLAY 1.234043 (2525 4250);
PAINT GREEN (2525 4250);
DISPLAY INVISIBLE (2525 4250);
FORCEPROP 1 LAST HDL_TAP TRUE
J 2
(2200 4175);
DISPLAY 1.234043 (2200 4175);
PAINT GREEN (2200 4175);
DISPLAY INVISIBLE (2200 4175);
FORCEPROP 1 LAST PATH I174
J 2
(2527 4300);
DISPLAY 0.872340 (2527 4300);
PAINT GREEN (2527 4300);
DISPLAY INVISIBLE (2527 4300);
FORCEADD TAP..6
R 2
(2525 4700);
FORCEPROP 3 LASTPIN (2475 4700) SIG_NAME M_E_DQS_DN<17>
J 0
(2485 4710);
DISPLAY 0.659574 (2485 4710);
PAINT MONO (2485 4710);
DISPLAY INVISIBLE (2485 4710);
FORCEPROP 1 LASTPIN (2475 4700) BN 17
J 2
(2525 4710);
DISPLAY 0.617021 (2525 4710);
PAINT PINK (2525 4710);
FORCEPROP 2 LAST CDS_LIB mstr_standard
J 2
(2525 4700);
DISPLAY 0.787234 (2525 4700);
PAINT MONO (2525 4700);
DISPLAY INVISIBLE (2525 4700);
FORCEPROP 1 LAST BODY_TYPE PLUMBING
J 2
(2525 4650);
DISPLAY 1.234043 (2525 4650);
PAINT GREEN (2525 4650);
DISPLAY INVISIBLE (2525 4650);
FORCEPROP 1 LAST HDL_TAP TRUE
J 2
(2200 4575);
DISPLAY 1.234043 (2200 4575);
PAINT GREEN (2200 4575);
DISPLAY INVISIBLE (2200 4575);
FORCEPROP 1 LAST PATH I175
J 2
(2527 4700);
DISPLAY 0.872340 (2527 4700);
PAINT GREEN (2527 4700);
DISPLAY INVISIBLE (2527 4700);
FORCEADD TAP..6
R 2
(2525 4600);
FORCEPROP 3 LASTPIN (2475 4600) SIG_NAME M_E_DQS_DN<16>
J 0
(2485 4610);
DISPLAY 0.659574 (2485 4610);
PAINT MONO (2485 4610);
DISPLAY INVISIBLE (2485 4610);
FORCEPROP 1 LASTPIN (2475 4600) BN 16
J 2
(2525 4610);
DISPLAY 0.617021 (2525 4610);
PAINT PINK (2525 4610);
FORCEPROP 2 LAST CDS_LIB mstr_standard
J 0
(2525 4600);
DISPLAY 0.787234 (2525 4600);
PAINT MONO (2525 4600);
DISPLAY INVISIBLE (2525 4600);
FORCEPROP 1 LAST BODY_TYPE PLUMBING
J 2
(2525 4550);
DISPLAY 1.234043 (2525 4550);
PAINT GREEN (2525 4550);
DISPLAY INVISIBLE (2525 4550);
FORCEPROP 1 LAST HDL_TAP TRUE
J 2
(2200 4475);
DISPLAY 1.234043 (2200 4475);
PAINT GREEN (2200 4475);
DISPLAY INVISIBLE (2200 4475);
FORCEPROP 1 LAST PATH I176
J 2
(2527 4600);
DISPLAY 0.872340 (2527 4600);
PAINT GREEN (2527 4600);
DISPLAY INVISIBLE (2527 4600);
FORCEADD TAP..6
R 2
(2525 4500);
FORCEPROP 3 LASTPIN (2475 4500) SIG_NAME M_E_DQS_DN<15>
J 0
(2485 4510);
DISPLAY 0.659574 (2485 4510);
PAINT MONO (2485 4510);
DISPLAY INVISIBLE (2485 4510);
FORCEPROP 1 LASTPIN (2475 4500) BN 15
J 2
(2525 4510);
DISPLAY 0.617021 (2525 4510);
PAINT PINK (2525 4510);
FORCEPROP 2 LAST CDS_LIB mstr_standard
J 0
(2525 4500);
DISPLAY 0.787234 (2525 4500);
PAINT MONO (2525 4500);
DISPLAY INVISIBLE (2525 4500);
FORCEPROP 1 LAST BODY_TYPE PLUMBING
J 2
(2525 4450);
DISPLAY 1.234043 (2525 4450);
PAINT GREEN (2525 4450);
DISPLAY INVISIBLE (2525 4450);
FORCEPROP 1 LAST HDL_TAP TRUE
J 2
(2200 4375);
DISPLAY 1.234043 (2200 4375);
PAINT GREEN (2200 4375);
DISPLAY INVISIBLE (2200 4375);
FORCEPROP 1 LAST PATH I177
J 2
(2527 4500);
DISPLAY 0.872340 (2527 4500);
PAINT GREEN (2527 4500);
DISPLAY INVISIBLE (2527 4500);
FORCEADD TAP..6
R 2
(2325 4750);
FORCEPROP 3 LASTPIN (2275 4750) SIG_NAME M_E_DQS_DP<17>
J 0
(2285 4760);
DISPLAY 0.659574 (2285 4760);
PAINT MONO (2285 4760);
DISPLAY INVISIBLE (2285 4760);
FORCEPROP 1 LASTPIN (2275 4750) BN 17
J 2
(2325 4760);
DISPLAY 0.617021 (2325 4760);
PAINT PINK (2325 4760);
FORCEPROP 2 LAST CDS_LIB mstr_standard
J 2
(2325 4750);
DISPLAY 0.787234 (2325 4750);
PAINT MONO (2325 4750);
DISPLAY INVISIBLE (2325 4750);
FORCEPROP 1 LAST BODY_TYPE PLUMBING
J 2
(2325 4700);
DISPLAY 1.234043 (2325 4700);
PAINT GREEN (2325 4700);
DISPLAY INVISIBLE (2325 4700);
FORCEPROP 1 LAST HDL_TAP TRUE
J 2
(2000 4625);
DISPLAY 1.234043 (2000 4625);
PAINT GREEN (2000 4625);
DISPLAY INVISIBLE (2000 4625);
FORCEPROP 1 LAST PATH I178
J 2
(2327 4750);
DISPLAY 0.872340 (2327 4750);
PAINT GREEN (2327 4750);
DISPLAY INVISIBLE (2327 4750);
FORCEADD OFFPAGE..3
(3225 4750);
FORCEPROP 2 LAST $XR0 27 
J 0
(3439 4750);
DISPLAY 0.638298 (3439 4750);
PAINT MONO (3439 4750);
FORCEPROP 2 LAST $XR1 51 
J 0
(3529 4750);
DISPLAY 0.638298 (3529 4750);
PAINT MONO (3529 4750);
FORCEPROP 2 LAST CDS_LIB mstr_standard
J 0
(3225 4750);
DISPLAY 0.787234 (3225 4750);
PAINT MONO (3225 4750);
DISPLAY INVISIBLE (3225 4750);
FORCEPROP 1 LAST OFFPAGE TRUE
J 0
(3550 4625);
DISPLAY 0.936170 (3550 4625);
PAINT GREEN (3550 4625);
DISPLAY INVISIBLE (3550 4625);
FORCEPROP 1 LAST COMMENT_BODY TRUE
J 0
(3175 4650);
DISPLAY 0.936170 (3175 4650);
PAINT GREEN (3175 4650);
DISPLAY INVISIBLE (3175 4650);
FORCEPROP 2 LAST PATH I179
J 0
(3450 4800);
DISPLAY 1.021277 (3450 4800);
PAINT ORANGE (3450 4800);
DISPLAY INVISIBLE (3450 4800);
FORCEADD OFFPAGE..1
(-2275 2650);
FORCEPROP 2 LAST $XR0 27 
J 0
(-2496 2650);
DISPLAY 0.638298 (-2496 2650);
PAINT MONO (-2496 2650);
FORCEPROP 2 LAST $XR1 51 
J 0
(-2586 2650);
DISPLAY 0.638298 (-2586 2650);
PAINT MONO (-2586 2650);
FORCEPROP 2 LAST CDS_LIB mstr_standard
J 0
(-2275 2650);
DISPLAY 0.787234 (-2275 2650);
PAINT MONO (-2275 2650);
DISPLAY INVISIBLE (-2275 2650);
FORCEPROP 1 LAST OFFPAGE TRUE
J 0
(-1950 2525);
DISPLAY 0.936170 (-1950 2525);
PAINT GREEN (-1950 2525);
DISPLAY INVISIBLE (-1950 2525);
FORCEPROP 1 LAST COMMENT_BODY TRUE
J 0
(-2150 2550);
DISPLAY 0.936170 (-2150 2550);
PAINT GREEN (-2150 2550);
DISPLAY INVISIBLE (-2150 2550);
FORCEPROP 2 LAST PATH I18
J 0
(-2475 2700);
DISPLAY 1.021277 (-2475 2700);
PAINT ORANGE (-2475 2700);
DISPLAY INVISIBLE (-2475 2700);
FORCEADD OFFPAGE..3
(3225 4800);
FORCEPROP 2 LAST $XR0 27 
J 0
(3439 4800);
DISPLAY 0.638298 (3439 4800);
PAINT MONO (3439 4800);
FORCEPROP 2 LAST $XR1 51 
J 0
(3529 4800);
DISPLAY 0.638298 (3529 4800);
PAINT MONO (3529 4800);
FORCEPROP 2 LAST CDS_LIB mstr_standard
J 0
(3225 4800);
DISPLAY 0.787234 (3225 4800);
PAINT MONO (3225 4800);
DISPLAY INVISIBLE (3225 4800);
FORCEPROP 1 LAST OFFPAGE TRUE
J 0
(3550 4675);
DISPLAY 0.936170 (3550 4675);
PAINT GREEN (3550 4675);
DISPLAY INVISIBLE (3550 4675);
FORCEPROP 1 LAST COMMENT_BODY TRUE
J 0
(3175 4700);
DISPLAY 0.936170 (3175 4700);
PAINT GREEN (3175 4700);
DISPLAY INVISIBLE (3175 4700);
FORCEPROP 2 LAST PATH I180
J 0
(3450 4850);
DISPLAY 1.021277 (3450 4850);
PAINT ORANGE (3450 4850);
DISPLAY INVISIBLE (3450 4850);
FORCEADD P12V_NVDIMM_DEF..1
(2175 2725);
FORCEPROP 3 LASTPIN (2175 2675) SIG_NAME P12V_NVDIMM_DEF\g
J 0
(2185 2685);
DISPLAY 0.659574 (2185 2685);
PAINT MONO (2185 2685);
DISPLAY INVISIBLE (2185 2685);
FORCEPROP 1 LAST VOLTAGE 12.0
J 0
(2130 2682);
DISPLAY 0.340426 (2130 2682);
PAINT SKYBLUE (2130 2682);
DISPLAY INVISIBLE (2130 2682);
FORCEPROP 2 LAST CDS_LIB mstr_symbols
J 0
(2175 2725);
PAINT ORANGE (2175 2725);
DISPLAY INVISIBLE (2175 2725);
FORCEPROP 1 LAST BODY_TYPE PLUMBING
J 0
(2130 2682);
DISPLAY 0.340426 (2130 2682);
PAINT GREEN (2130 2682);
DISPLAY INVISIBLE (2130 2682);
FORCEPROP 1 LAST PATH I181
J 0
(2225 2750);
DISPLAY 0.872340 (2225 2750);
PAINT AQUA (2225 2750);
DISPLAY INVISIBLE (2225 2750);
FORCEPROP 1 LAST HDL_POWER P12V_NVDIMM_DEF
J 1
(2175 2775);
DISPLAY 0.872340 (2175 2775);
PAINT GREEN (2175 2775);
DISPLAY INVISIBLE (2175 2775);
FORCEADD TAP..6
(-1475 2100);
FORCEPROP 3 LASTPIN (-1425 2100) SIG_NAME M_E_ECC<0>
J 0
(-1415 2110);
DISPLAY 0.659574 (-1415 2110);
PAINT MONO (-1415 2110);
DISPLAY INVISIBLE (-1415 2110);
FORCEPROP 1 LASTPIN (-1425 2100) BN 0
J 0
(-1475 2110);
DISPLAY 0.617021 (-1475 2110);
PAINT PINK (-1475 2110);
FORCEPROP 2 LAST CDS_LIB mstr_standard
J 0
(-1475 2100);
DISPLAY 0.787234 (-1475 2100);
PAINT MONO (-1475 2100);
DISPLAY INVISIBLE (-1475 2100);
FORCEPROP 1 LAST BODY_TYPE PLUMBING
J 0
(-1475 2050);
DISPLAY 1.234043 (-1475 2050);
PAINT GREEN (-1475 2050);
DISPLAY INVISIBLE (-1475 2050);
FORCEPROP 1 LAST HDL_TAP TRUE
J 0
(-1150 1975);
DISPLAY 1.234043 (-1150 1975);
PAINT GREEN (-1150 1975);
DISPLAY INVISIBLE (-1150 1975);
FORCEPROP 1 LAST PATH I19
J 0
(-1477 2100);
DISPLAY 0.872340 (-1477 2100);
PAINT GREEN (-1477 2100);
DISPLAY INVISIBLE (-1477 2100);
FORCEADD GND..1
R 2
(-3025 900);
FORCEPROP 3 LASTPIN (-3025 950) SIG_NAME GND\g
J 0
(-3015 960);
DISPLAY 0.659574 (-3015 960);
PAINT MONO (-3015 960);
DISPLAY INVISIBLE (-3015 960);
FORCEPROP 1 LAST VOLTAGE 0
J 0
(-3025 900);
PAINT SKYBLUE (-3025 900);
DISPLAY INVISIBLE (-3025 900);
FORCEPROP 1 LAST SIZE 1B
J 2
(-3100 850);
DISPLAY 1.787234 (-3100 850);
PAINT GREEN (-3100 850);
DISPLAY INVISIBLE (-3100 850);
FORCEPROP 2 LAST CDS_LIB mstr_symbols
J 2
(-3025 900);
PAINT ORANGE (-3025 900);
DISPLAY INVISIBLE (-3025 900);
FORCEPROP 1 LAST BODY_TYPE PLUMBING
J 2
(-2980 857);
DISPLAY 0.340426 (-2980 857);
PAINT GREEN (-2980 857);
DISPLAY INVISIBLE (-2980 857);
FORCEPROP 1 LAST PATH I2
J 2
(-3100 900);
DISPLAY 0.872340 (-3100 900);
PAINT AQUA (-3100 900);
DISPLAY INVISIBLE (-3100 900);
FORCEPROP 1 LAST HDL_POWER GND
J 2
(-3025 1050);
DISPLAY 1.404255 (-3025 1050);
PAINT GREEN (-3025 1050);
DISPLAY INVISIBLE (-3025 1050);
FORCEADD TAP..6
(-1475 2150);
FORCEPROP 3 LASTPIN (-1425 2150) SIG_NAME M_E_ECC<1>
J 0
(-1415 2160);
DISPLAY 0.659574 (-1415 2160);
PAINT MONO (-1415 2160);
DISPLAY INVISIBLE (-1415 2160);
FORCEPROP 1 LASTPIN (-1425 2150) BN 1
J 0
(-1475 2160);
DISPLAY 0.617021 (-1475 2160);
PAINT PINK (-1475 2160);
FORCEPROP 2 LAST CDS_LIB mstr_standard
J 0
(-1475 2150);
DISPLAY 0.787234 (-1475 2150);
PAINT MONO (-1475 2150);
DISPLAY INVISIBLE (-1475 2150);
FORCEPROP 1 LAST BODY_TYPE PLUMBING
J 0
(-1475 2100);
DISPLAY 1.234043 (-1475 2100);
PAINT GREEN (-1475 2100);
DISPLAY INVISIBLE (-1475 2100);
FORCEPROP 1 LAST HDL_TAP TRUE
J 0
(-1150 2025);
DISPLAY 1.234043 (-1150 2025);
PAINT GREEN (-1150 2025);
DISPLAY INVISIBLE (-1150 2025);
FORCEPROP 1 LAST PATH I20
J 0
(-1477 2150);
DISPLAY 0.872340 (-1477 2150);
PAINT GREEN (-1477 2150);
DISPLAY INVISIBLE (-1477 2150);
FORCEADD TAP..6
(-1475 2250);
FORCEPROP 3 LASTPIN (-1425 2250) SIG_NAME M_E_ECC<3>
J 0
(-1415 2260);
DISPLAY 0.659574 (-1415 2260);
PAINT MONO (-1415 2260);
DISPLAY INVISIBLE (-1415 2260);
FORCEPROP 1 LASTPIN (-1425 2250) BN 3
J 0
(-1475 2260);
DISPLAY 0.617021 (-1475 2260);
PAINT PINK (-1475 2260);
FORCEPROP 2 LAST CDS_LIB mstr_standard
J 0
(-1475 2250);
DISPLAY 0.787234 (-1475 2250);
PAINT MONO (-1475 2250);
DISPLAY INVISIBLE (-1475 2250);
FORCEPROP 1 LAST BODY_TYPE PLUMBING
J 0
(-1475 2200);
DISPLAY 1.234043 (-1475 2200);
PAINT GREEN (-1475 2200);
DISPLAY INVISIBLE (-1475 2200);
FORCEPROP 1 LAST HDL_TAP TRUE
J 0
(-1150 2125);
DISPLAY 1.234043 (-1150 2125);
PAINT GREEN (-1150 2125);
DISPLAY INVISIBLE (-1150 2125);
FORCEPROP 1 LAST PATH I21
J 0
(-1477 2250);
DISPLAY 0.872340 (-1477 2250);
PAINT GREEN (-1477 2250);
DISPLAY INVISIBLE (-1477 2250);
FORCEADD TAP..6
(-1475 2200);
FORCEPROP 3 LASTPIN (-1425 2200) SIG_NAME M_E_ECC<2>
J 0
(-1415 2210);
DISPLAY 0.659574 (-1415 2210);
PAINT MONO (-1415 2210);
DISPLAY INVISIBLE (-1415 2210);
FORCEPROP 1 LASTPIN (-1425 2200) BN 2
J 0
(-1475 2210);
DISPLAY 0.617021 (-1475 2210);
PAINT PINK (-1475 2210);
FORCEPROP 2 LAST CDS_LIB mstr_standard
J 0
(-1475 2200);
DISPLAY 0.787234 (-1475 2200);
PAINT MONO (-1475 2200);
DISPLAY INVISIBLE (-1475 2200);
FORCEPROP 1 LAST BODY_TYPE PLUMBING
J 0
(-1475 2150);
DISPLAY 1.234043 (-1475 2150);
PAINT GREEN (-1475 2150);
DISPLAY INVISIBLE (-1475 2150);
FORCEPROP 1 LAST HDL_TAP TRUE
J 0
(-1150 2075);
DISPLAY 1.234043 (-1150 2075);
PAINT GREEN (-1150 2075);
DISPLAY INVISIBLE (-1150 2075);
FORCEPROP 1 LAST PATH I22
J 0
(-1477 2200);
DISPLAY 0.872340 (-1477 2200);
PAINT GREEN (-1477 2200);
DISPLAY INVISIBLE (-1477 2200);
FORCEADD TAP..6
(-1475 2350);
FORCEPROP 3 LASTPIN (-1425 2350) SIG_NAME M_E_ECC<5>
J 0
(-1415 2360);
DISPLAY 0.659574 (-1415 2360);
PAINT MONO (-1415 2360);
DISPLAY INVISIBLE (-1415 2360);
FORCEPROP 1 LASTPIN (-1425 2350) BN 5
J 0
(-1475 2360);
DISPLAY 0.617021 (-1475 2360);
PAINT PINK (-1475 2360);
FORCEPROP 2 LAST CDS_LIB mstr_standard
J 0
(-1475 2350);
DISPLAY 0.787234 (-1475 2350);
PAINT MONO (-1475 2350);
DISPLAY INVISIBLE (-1475 2350);
FORCEPROP 1 LAST BODY_TYPE PLUMBING
J 0
(-1475 2300);
DISPLAY 1.234043 (-1475 2300);
PAINT GREEN (-1475 2300);
DISPLAY INVISIBLE (-1475 2300);
FORCEPROP 1 LAST HDL_TAP TRUE
J 0
(-1150 2225);
DISPLAY 1.234043 (-1150 2225);
PAINT GREEN (-1150 2225);
DISPLAY INVISIBLE (-1150 2225);
FORCEPROP 1 LAST PATH I23
J 0
(-1477 2350);
DISPLAY 0.872340 (-1477 2350);
PAINT GREEN (-1477 2350);
DISPLAY INVISIBLE (-1477 2350);
FORCEADD TAP..6
(-1475 2300);
FORCEPROP 3 LASTPIN (-1425 2300) SIG_NAME M_E_ECC<4>
J 0
(-1415 2310);
DISPLAY 0.659574 (-1415 2310);
PAINT MONO (-1415 2310);
DISPLAY INVISIBLE (-1415 2310);
FORCEPROP 1 LASTPIN (-1425 2300) BN 4
J 0
(-1475 2310);
DISPLAY 0.617021 (-1475 2310);
PAINT PINK (-1475 2310);
FORCEPROP 2 LAST CDS_LIB mstr_standard
J 0
(-1475 2300);
DISPLAY 0.787234 (-1475 2300);
PAINT MONO (-1475 2300);
DISPLAY INVISIBLE (-1475 2300);
FORCEPROP 1 LAST BODY_TYPE PLUMBING
J 0
(-1475 2250);
DISPLAY 1.234043 (-1475 2250);
PAINT GREEN (-1475 2250);
DISPLAY INVISIBLE (-1475 2250);
FORCEPROP 1 LAST HDL_TAP TRUE
J 0
(-1150 2175);
DISPLAY 1.234043 (-1150 2175);
PAINT GREEN (-1150 2175);
DISPLAY INVISIBLE (-1150 2175);
FORCEPROP 1 LAST PATH I24
J 0
(-1477 2300);
DISPLAY 0.872340 (-1477 2300);
PAINT GREEN (-1477 2300);
DISPLAY INVISIBLE (-1477 2300);
FORCEADD TAP..6
(-1475 2400);
FORCEPROP 3 LASTPIN (-1425 2400) SIG_NAME M_E_ECC<6>
J 0
(-1415 2410);
DISPLAY 0.659574 (-1415 2410);
PAINT MONO (-1415 2410);
DISPLAY INVISIBLE (-1415 2410);
FORCEPROP 1 LASTPIN (-1425 2400) BN 6
J 0
(-1475 2410);
DISPLAY 0.617021 (-1475 2410);
PAINT PINK (-1475 2410);
FORCEPROP 2 LAST CDS_LIB mstr_standard
J 0
(-1475 2400);
DISPLAY 0.787234 (-1475 2400);
PAINT MONO (-1475 2400);
DISPLAY INVISIBLE (-1475 2400);
FORCEPROP 1 LAST BODY_TYPE PLUMBING
J 0
(-1475 2350);
DISPLAY 1.234043 (-1475 2350);
PAINT GREEN (-1475 2350);
DISPLAY INVISIBLE (-1475 2350);
FORCEPROP 1 LAST HDL_TAP TRUE
J 0
(-1150 2275);
DISPLAY 1.234043 (-1150 2275);
PAINT GREEN (-1150 2275);
DISPLAY INVISIBLE (-1150 2275);
FORCEPROP 1 LAST PATH I25
J 0
(-1477 2400);
DISPLAY 0.872340 (-1477 2400);
PAINT GREEN (-1477 2400);
DISPLAY INVISIBLE (-1477 2400);
FORCEADD TAP..6
(-1475 2450);
FORCEPROP 3 LASTPIN (-1425 2450) SIG_NAME M_E_ECC<7>
J 0
(-1415 2460);
DISPLAY 0.659574 (-1415 2460);
PAINT MONO (-1415 2460);
DISPLAY INVISIBLE (-1415 2460);
FORCEPROP 1 LASTPIN (-1425 2450) BN 7
J 0
(-1475 2460);
DISPLAY 0.617021 (-1475 2460);
PAINT PINK (-1475 2460);
FORCEPROP 2 LAST CDS_LIB mstr_standard
J 0
(-1475 2450);
DISPLAY 0.787234 (-1475 2450);
PAINT MONO (-1475 2450);
DISPLAY INVISIBLE (-1475 2450);
FORCEPROP 1 LAST BODY_TYPE PLUMBING
J 0
(-1475 2400);
DISPLAY 1.234043 (-1475 2400);
PAINT GREEN (-1475 2400);
DISPLAY INVISIBLE (-1475 2400);
FORCEPROP 1 LAST HDL_TAP TRUE
J 0
(-1150 2325);
DISPLAY 1.234043 (-1150 2325);
PAINT GREEN (-1150 2325);
DISPLAY INVISIBLE (-1150 2325);
FORCEPROP 1 LAST PATH I26
J 0
(-1477 2450);
DISPLAY 0.872340 (-1477 2450);
PAINT GREEN (-1477 2450);
DISPLAY INVISIBLE (-1477 2450);
FORCEADD TAP..6
(-1475 2600);
FORCEPROP 3 LASTPIN (-1425 2600) SIG_NAME M_E_ODT<3>
J 0
(-1415 2610);
DISPLAY 0.659574 (-1415 2610);
PAINT MONO (-1415 2610);
DISPLAY INVISIBLE (-1415 2610);
FORCEPROP 1 LASTPIN (-1425 2600) BN 3
J 0
(-1475 2610);
DISPLAY 0.617021 (-1475 2610);
PAINT PINK (-1475 2610);
FORCEPROP 2 LAST CDS_LIB mstr_standard
J 0
(-1475 2600);
DISPLAY 0.787234 (-1475 2600);
PAINT MONO (-1475 2600);
DISPLAY INVISIBLE (-1475 2600);
FORCEPROP 1 LAST BODY_TYPE PLUMBING
J 0
(-1475 2550);
DISPLAY 1.234043 (-1475 2550);
PAINT GREEN (-1475 2550);
DISPLAY INVISIBLE (-1475 2550);
FORCEPROP 1 LAST HDL_TAP TRUE
J 0
(-1150 2475);
DISPLAY 1.234043 (-1150 2475);
PAINT GREEN (-1150 2475);
DISPLAY INVISIBLE (-1150 2475);
FORCEPROP 1 LAST PATH I27
J 0
(-1477 2600);
DISPLAY 0.872340 (-1477 2600);
PAINT GREEN (-1477 2600);
DISPLAY INVISIBLE (-1477 2600);
FORCEADD TAP..6
(-1475 2550);
FORCEPROP 3 LASTPIN (-1425 2550) SIG_NAME M_E_ODT<2>
J 0
(-1415 2560);
DISPLAY 0.659574 (-1415 2560);
PAINT MONO (-1415 2560);
DISPLAY INVISIBLE (-1415 2560);
FORCEPROP 1 LASTPIN (-1425 2550) BN 2
J 0
(-1475 2560);
DISPLAY 0.617021 (-1475 2560);
PAINT PINK (-1475 2560);
FORCEPROP 2 LAST CDS_LIB mstr_standard
J 0
(-1475 2550);
DISPLAY 0.787234 (-1475 2550);
PAINT MONO (-1475 2550);
DISPLAY INVISIBLE (-1475 2550);
FORCEPROP 1 LAST BODY_TYPE PLUMBING
J 0
(-1475 2500);
DISPLAY 1.234043 (-1475 2500);
PAINT GREEN (-1475 2500);
DISPLAY INVISIBLE (-1475 2500);
FORCEPROP 1 LAST HDL_TAP TRUE
J 0
(-1150 2425);
DISPLAY 1.234043 (-1150 2425);
PAINT GREEN (-1150 2425);
DISPLAY INVISIBLE (-1150 2425);
FORCEPROP 1 LAST PATH I28
J 0
(-1477 2550);
DISPLAY 0.872340 (-1477 2550);
PAINT GREEN (-1477 2550);
DISPLAY INVISIBLE (-1477 2550);
FORCEADD OFFPAGE..1
(-2275 2800);
FORCEPROP 2 LAST $XR0 27 
J 0
(-2496 2800);
DISPLAY 0.638298 (-2496 2800);
PAINT MONO (-2496 2800);
FORCEPROP 2 LAST $XR1 51 
J 0
(-2586 2800);
DISPLAY 0.638298 (-2586 2800);
PAINT MONO (-2586 2800);
FORCEPROP 2 LAST CDS_LIB mstr_standard
J 0
(-2275 2800);
DISPLAY 0.787234 (-2275 2800);
PAINT MONO (-2275 2800);
DISPLAY INVISIBLE (-2275 2800);
FORCEPROP 1 LAST OFFPAGE TRUE
J 0
(-1950 2675);
DISPLAY 0.936170 (-1950 2675);
PAINT GREEN (-1950 2675);
DISPLAY INVISIBLE (-1950 2675);
FORCEPROP 1 LAST COMMENT_BODY TRUE
J 0
(-2150 2700);
DISPLAY 0.936170 (-2150 2700);
PAINT GREEN (-2150 2700);
DISPLAY INVISIBLE (-2150 2700);
FORCEPROP 2 LAST PATH I29
J 0
(-2475 2850);
DISPLAY 1.021277 (-2475 2850);
PAINT ORANGE (-2475 2850);
DISPLAY INVISIBLE (-2475 2850);
FORCEADD CAP_A..1
R 2
(-3025 1150);
FORCEPROP 1 LAST LOCATION C4A18
J 2
(-3075 1250);
DISPLAY 0.617021 (-3075 1250);
PAINT AQUA (-3075 1250);
FORCEPROP 1 LAST PART_NUMBER A36096-045
J 2
(-3075 1000);
DISPLAY 0.617021 (-3075 1000);
PAINT BLUE (-3075 1000);
FORCEPROP 1 LAST VALUE 0.01UF
J 2
(-3075 1200);
DISPLAY 0.617021 (-3075 1200);
PAINT SKYBLUE (-3075 1200);
FORCEPROP 1 LAST TOLERANCE 10%
J 2
(-3075 1100);
DISPLAY 0.617021 (-3075 1100);
PAINT SKYBLUE (-3075 1100);
FORCEPROP 1 LAST PACK_TYPE 0402V
J 2
(-3075 950);
DISPLAY 0.617021 (-3075 950);
PAINT SKYBLUE (-3075 950);
FORCEPROP 1 LAST VOLTAGE 25V
J 2
(-3075 1150);
DISPLAY 0.617021 (-3075 1150);
PAINT SKYBLUE (-3075 1150);
FORCEPROP 1 LAST MATERIAL X7R
J 2
(-3075 1050);
DISPLAY 0.617021 (-3075 1050);
PAINT SKYBLUE (-3075 1050);
FORCEPROP 2 LAST CDS_LOCATION C4A18
J 2
(-3075 1250);
DISPLAY 0.617021 (-3075 1250);
PAINT AQUA (-3075 1250);
DISPLAY INVISIBLE (-3075 1250);
FORCEPROP 2 LAST BOM_COST MEM
J 0
(-3075 1350);
DISPLAY 1.021277 (-3075 1350);
PAINT ORANGE (-3075 1350);
DISPLAY INVISIBLE (-3075 1350);
FORCEPROP 2 LAST CDS_LIB dev_discrete
J 0
(-3025 1150);
PAINT ORANGE (-3025 1150);
DISPLAY INVISIBLE (-3025 1150);
FORCEPROP 2 LAST CDS_SEC 1
J 0
(-3075 1350);
DISPLAY 1.021277 (-3075 1350);
PAINT ORANGE (-3075 1350);
DISPLAY INVISIBLE (-3075 1350);
FORCEPROP 2 LAST $SEC 1
J 0
(-3075 1350);
PAINT MONO (-3075 1350);
DISPLAY INVISIBLE (-3075 1350);
FORCEPROP 1 LAST PATH I3
J 2
(-3075 1300);
DISPLAY 0.978723 (-3075 1300);
PAINT WHITE (-3075 1300);
DISPLAY INVISIBLE (-3075 1300);
FORCEPROP 2 LAST ROOM DDR4_CH_E
J 0
(-3075 1300);
DISPLAY 1.021277 (-3075 1300);
PAINT ORANGE (-3075 1300);
DISPLAY INVISIBLE (-3075 1300);
FORCEPROP 1 LASTPIN (-3025 1250) $PN 1
J 2
(-3035 1230);
DISPLAY 0.787234 (-3035 1230);
PAINT ORANGE (-3035 1230);
DISPLAY INVISIBLE (-3035 1230);
FORCEPROP 1 LASTPIN (-3025 1050) $PN 2
J 2
(-3035 1030);
DISPLAY 0.787234 (-3035 1030);
PAINT ORANGE (-3035 1030);
DISPLAY INVISIBLE (-3035 1030);
FORCEADD OFFPAGE..1
(-2275 3050);
FORCEPROP 2 LAST $XR0 27 
J 0
(-2496 3050);
DISPLAY 0.638298 (-2496 3050);
PAINT MONO (-2496 3050);
FORCEPROP 2 LAST $XR1 51 
J 0
(-2586 3050);
DISPLAY 0.638298 (-2586 3050);
PAINT MONO (-2586 3050);
FORCEPROP 2 LAST CDS_LIB mstr_standard
J 0
(-2275 3050);
DISPLAY 0.787234 (-2275 3050);
PAINT MONO (-2275 3050);
DISPLAY INVISIBLE (-2275 3050);
FORCEPROP 1 LAST OFFPAGE TRUE
J 0
(-1950 2925);
DISPLAY 0.936170 (-1950 2925);
PAINT GREEN (-1950 2925);
DISPLAY INVISIBLE (-1950 2925);
FORCEPROP 1 LAST COMMENT_BODY TRUE
J 0
(-2150 2950);
DISPLAY 0.936170 (-2150 2950);
PAINT GREEN (-2150 2950);
DISPLAY INVISIBLE (-2150 2950);
FORCEPROP 2 LAST PATH I30
J 0
(-2475 3100);
DISPLAY 1.021277 (-2475 3100);
PAINT ORANGE (-2475 3100);
DISPLAY INVISIBLE (-2475 3100);
FORCEADD OFFPAGE..1
(-2275 3100);
FORCEPROP 2 LAST $XR0 27 
J 0
(-2496 3100);
DISPLAY 0.638298 (-2496 3100);
PAINT MONO (-2496 3100);
FORCEPROP 2 LAST $XR1 51 
J 0
(-2586 3100);
DISPLAY 0.638298 (-2586 3100);
PAINT MONO (-2586 3100);
FORCEPROP 2 LAST CDS_LIB mstr_standard
J 0
(-2275 3100);
DISPLAY 0.787234 (-2275 3100);
PAINT MONO (-2275 3100);
DISPLAY INVISIBLE (-2275 3100);
FORCEPROP 1 LAST OFFPAGE TRUE
J 0
(-1950 2975);
DISPLAY 0.936170 (-1950 2975);
PAINT GREEN (-1950 2975);
DISPLAY INVISIBLE (-1950 2975);
FORCEPROP 1 LAST COMMENT_BODY TRUE
J 0
(-2150 3000);
DISPLAY 0.936170 (-2150 3000);
PAINT GREEN (-2150 3000);
DISPLAY INVISIBLE (-2150 3000);
FORCEPROP 2 LAST PATH I31
J 0
(-2475 3150);
DISPLAY 1.021277 (-2475 3150);
PAINT ORANGE (-2475 3150);
DISPLAY INVISIBLE (-2475 3150);
FORCEADD TAP..6
(-2025 3150);
FORCEPROP 3 LASTPIN (-1975 3150) SIG_NAME M_E_CLK_DN<2>
J 0
(-1965 3160);
DISPLAY 0.659574 (-1965 3160);
PAINT MONO (-1965 3160);
DISPLAY INVISIBLE (-1965 3160);
FORCEPROP 1 LASTPIN (-1975 3150) BN 2
J 0
(-2025 3160);
DISPLAY 0.617021 (-2025 3160);
PAINT PINK (-2025 3160);
FORCEPROP 2 LAST CDS_LIB mstr_standard
J 0
(-2025 3150);
DISPLAY 0.787234 (-2025 3150);
PAINT MONO (-2025 3150);
DISPLAY INVISIBLE (-2025 3150);
FORCEPROP 1 LAST BODY_TYPE PLUMBING
J 0
(-2025 3100);
DISPLAY 1.234043 (-2025 3100);
PAINT GREEN (-2025 3100);
DISPLAY INVISIBLE (-2025 3100);
FORCEPROP 1 LAST HDL_TAP TRUE
J 0
(-1700 3025);
DISPLAY 1.234043 (-1700 3025);
PAINT GREEN (-1700 3025);
DISPLAY INVISIBLE (-1700 3025);
FORCEPROP 1 LAST PATH I32
J 0
(-2027 3150);
DISPLAY 0.872340 (-2027 3150);
PAINT GREEN (-2027 3150);
DISPLAY INVISIBLE (-2027 3150);
FORCEADD OFFPAGE..1
(-2275 3500);
FORCEPROP 2 LAST $XR0 27 
J 0
(-2496 3500);
DISPLAY 0.638298 (-2496 3500);
PAINT MONO (-2496 3500);
FORCEPROP 2 LAST $XR1 51 
J 0
(-2586 3500);
DISPLAY 0.638298 (-2586 3500);
PAINT MONO (-2586 3500);
FORCEPROP 2 LAST CDS_LIB mstr_standard
J 0
(-2275 3500);
DISPLAY 0.787234 (-2275 3500);
PAINT MONO (-2275 3500);
DISPLAY INVISIBLE (-2275 3500);
FORCEPROP 1 LAST OFFPAGE TRUE
J 0
(-1950 3375);
DISPLAY 0.936170 (-1950 3375);
PAINT GREEN (-1950 3375);
DISPLAY INVISIBLE (-1950 3375);
FORCEPROP 1 LAST COMMENT_BODY TRUE
J 0
(-2150 3400);
DISPLAY 0.936170 (-2150 3400);
PAINT GREEN (-2150 3400);
DISPLAY INVISIBLE (-2150 3400);
FORCEPROP 2 LAST PATH I33
J 0
(-2475 3550);
DISPLAY 1.021277 (-2475 3550);
PAINT ORANGE (-2475 3550);
DISPLAY INVISIBLE (-2475 3550);
FORCEADD OFFPAGE..1
(-2275 3650);
FORCEPROP 2 LAST $XR0 27 
J 0
(-2496 3650);
DISPLAY 0.638298 (-2496 3650);
PAINT MONO (-2496 3650);
FORCEPROP 2 LAST $XR1 51 
J 0
(-2586 3650);
DISPLAY 0.638298 (-2586 3650);
PAINT MONO (-2586 3650);
FORCEPROP 2 LAST CDS_LIB mstr_standard
J 0
(-2275 3650);
DISPLAY 0.787234 (-2275 3650);
PAINT MONO (-2275 3650);
DISPLAY INVISIBLE (-2275 3650);
FORCEPROP 1 LAST OFFPAGE TRUE
J 0
(-1950 3525);
DISPLAY 0.936170 (-1950 3525);
PAINT GREEN (-1950 3525);
DISPLAY INVISIBLE (-1950 3525);
FORCEPROP 1 LAST COMMENT_BODY TRUE
J 0
(-2150 3550);
DISPLAY 0.936170 (-2150 3550);
PAINT GREEN (-2150 3550);
DISPLAY INVISIBLE (-2150 3550);
FORCEPROP 2 LAST PATH I34
J 0
(-2475 3700);
DISPLAY 1.021277 (-2475 3700);
PAINT ORANGE (-2475 3700);
DISPLAY INVISIBLE (-2475 3700);
FORCEADD TAP..6
(-2025 3250);
FORCEPROP 3 LASTPIN (-1975 3250) SIG_NAME M_E_CLK_DN<3>
J 0
(-1965 3260);
DISPLAY 0.659574 (-1965 3260);
PAINT MONO (-1965 3260);
DISPLAY INVISIBLE (-1965 3260);
FORCEPROP 1 LASTPIN (-1975 3250) BN 3
J 0
(-2027 3258);
DISPLAY 0.617021 (-2027 3258);
PAINT PINK (-2027 3258);
FORCEPROP 2 LAST CDS_LIB mstr_standard
J 0
(-2025 3250);
PAINT MONO (-2025 3250);
DISPLAY INVISIBLE (-2025 3250);
FORCEPROP 1 LAST BODY_TYPE PLUMBING
J 0
(-2025 3200);
DISPLAY 1.234043 (-2025 3200);
PAINT GREEN (-2025 3200);
DISPLAY INVISIBLE (-2025 3200);
FORCEPROP 1 LAST HDL_TAP TRUE
J 0
(-1700 3125);
DISPLAY 1.234043 (-1700 3125);
PAINT GREEN (-1700 3125);
DISPLAY INVISIBLE (-1700 3125);
FORCEPROP 1 LAST PATH I35
J 0
(-2027 3250);
DISPLAY 0.872340 (-2027 3250);
PAINT GREEN (-2027 3250);
DISPLAY INVISIBLE (-2027 3250);
FORCEADD TAP..6
(-1525 2750);
FORCEPROP 3 LASTPIN (-1475 2750) SIG_NAME M_E_CKE<3>
J 0
(-1465 2760);
DISPLAY 0.659574 (-1465 2760);
PAINT MONO (-1465 2760);
DISPLAY INVISIBLE (-1465 2760);
FORCEPROP 1 LASTPIN (-1475 2750) BN 3
J 0
(-1525 2760);
DISPLAY 0.617021 (-1525 2760);
PAINT PINK (-1525 2760);
FORCEPROP 2 LAST CDS_LIB mstr_standard
J 0
(-1525 2750);
DISPLAY 0.787234 (-1525 2750);
PAINT MONO (-1525 2750);
DISPLAY INVISIBLE (-1525 2750);
FORCEPROP 1 LAST BODY_TYPE PLUMBING
J 0
(-1525 2700);
DISPLAY 1.234043 (-1525 2700);
PAINT GREEN (-1525 2700);
DISPLAY INVISIBLE (-1525 2700);
FORCEPROP 1 LAST HDL_TAP TRUE
J 0
(-1200 2625);
DISPLAY 1.234043 (-1200 2625);
PAINT GREEN (-1200 2625);
DISPLAY INVISIBLE (-1200 2625);
FORCEPROP 1 LAST PATH I36
J 0
(-1527 2750);
DISPLAY 0.872340 (-1527 2750);
PAINT GREEN (-1527 2750);
DISPLAY INVISIBLE (-1527 2750);
FORCEADD TAP..6
(-1525 2700);
FORCEPROP 3 LASTPIN (-1475 2700) SIG_NAME M_E_CKE<2>
J 0
(-1465 2710);
DISPLAY 0.659574 (-1465 2710);
PAINT MONO (-1465 2710);
DISPLAY INVISIBLE (-1465 2710);
FORCEPROP 1 LASTPIN (-1475 2700) BN 2
J 0
(-1525 2710);
DISPLAY 0.617021 (-1525 2710);
PAINT PINK (-1525 2710);
FORCEPROP 2 LAST CDS_LIB mstr_standard
J 0
(-1525 2700);
DISPLAY 0.787234 (-1525 2700);
PAINT MONO (-1525 2700);
DISPLAY INVISIBLE (-1525 2700);
FORCEPROP 1 LAST BODY_TYPE PLUMBING
J 0
(-1525 2650);
DISPLAY 1.234043 (-1525 2650);
PAINT GREEN (-1525 2650);
DISPLAY INVISIBLE (-1525 2650);
FORCEPROP 1 LAST HDL_TAP TRUE
J 0
(-1200 2575);
DISPLAY 1.234043 (-1200 2575);
PAINT GREEN (-1200 2575);
DISPLAY INVISIBLE (-1200 2575);
FORCEPROP 1 LAST PATH I37
J 0
(-1527 2700);
DISPLAY 0.872340 (-1527 2700);
PAINT GREEN (-1527 2700);
DISPLAY INVISIBLE (-1527 2700);
FORCEADD TAP..6
(-1475 2900);
FORCEPROP 3 LASTPIN (-1425 2900) SIG_NAME M_E_CS_N<5>
J 0
(-1415 2910);
DISPLAY 0.659574 (-1415 2910);
PAINT MONO (-1415 2910);
DISPLAY INVISIBLE (-1415 2910);
FORCEPROP 1 LASTPIN (-1425 2900) BN 5
J 0
(-1475 2910);
DISPLAY 0.617021 (-1475 2910);
PAINT PINK (-1475 2910);
FORCEPROP 2 LAST CDS_LIB mstr_standard
J 0
(-1475 2900);
DISPLAY 0.787234 (-1475 2900);
PAINT MONO (-1475 2900);
DISPLAY INVISIBLE (-1475 2900);
FORCEPROP 1 LAST BODY_TYPE PLUMBING
J 0
(-1475 2850);
DISPLAY 1.234043 (-1475 2850);
PAINT GREEN (-1475 2850);
DISPLAY INVISIBLE (-1475 2850);
FORCEPROP 1 LAST HDL_TAP TRUE
J 0
(-1150 2775);
DISPLAY 1.234043 (-1150 2775);
PAINT GREEN (-1150 2775);
DISPLAY INVISIBLE (-1150 2775);
FORCEPROP 1 LAST PATH I38
J 0
(-1477 2900);
DISPLAY 0.872340 (-1477 2900);
PAINT GREEN (-1477 2900);
DISPLAY INVISIBLE (-1477 2900);
FORCEADD TAP..6
(-1475 2850);
FORCEPROP 3 LASTPIN (-1425 2850) SIG_NAME M_E_CS_N<4>
J 0
(-1415 2860);
DISPLAY 0.659574 (-1415 2860);
PAINT MONO (-1415 2860);
DISPLAY INVISIBLE (-1415 2860);
FORCEPROP 1 LASTPIN (-1425 2850) BN 4
J 0
(-1475 2860);
DISPLAY 0.617021 (-1475 2860);
PAINT PINK (-1475 2860);
FORCEPROP 2 LAST CDS_LIB mstr_standard
J 0
(-1475 2850);
DISPLAY 0.787234 (-1475 2850);
PAINT MONO (-1475 2850);
DISPLAY INVISIBLE (-1475 2850);
FORCEPROP 1 LAST BODY_TYPE PLUMBING
J 0
(-1475 2800);
DISPLAY 1.234043 (-1475 2800);
PAINT GREEN (-1475 2800);
DISPLAY INVISIBLE (-1475 2800);
FORCEPROP 1 LAST HDL_TAP TRUE
J 0
(-1150 2725);
DISPLAY 1.234043 (-1150 2725);
PAINT GREEN (-1150 2725);
DISPLAY INVISIBLE (-1150 2725);
FORCEPROP 1 LAST PATH I39
J 0
(-1477 2850);
DISPLAY 0.872340 (-1477 2850);
PAINT GREEN (-1477 2850);
DISPLAY INVISIBLE (-1477 2850);
FORCEADD OFFPAGE..1
(-3175 1350);
FORCEPROP 2 LAST $XR0 98 
J 0
(-3396 1350);
DISPLAY 0.638298 (-3396 1350);
PAINT MONO (-3396 1350);
FORCEPROP 2 LAST $XR1 51 
J 0
(-3486 1350);
DISPLAY 0.638298 (-3486 1350);
PAINT MONO (-3486 1350);
FORCEPROP 2 LAST CDS_LIB mstr_standard
J 0
(-3175 1350);
DISPLAY 0.787234 (-3175 1350);
PAINT MONO (-3175 1350);
DISPLAY INVISIBLE (-3175 1350);
FORCEPROP 1 LAST OFFPAGE TRUE
J 0
(-2850 1225);
DISPLAY 0.936170 (-2850 1225);
PAINT GREEN (-2850 1225);
DISPLAY INVISIBLE (-2850 1225);
FORCEPROP 1 LAST COMMENT_BODY TRUE
J 0
(-3050 1250);
DISPLAY 0.936170 (-3050 1250);
PAINT GREEN (-3050 1250);
DISPLAY INVISIBLE (-3050 1250);
FORCEPROP 2 LAST PATH I4
J 0
(-3425 1400);
DISPLAY 1.021277 (-3425 1400);
PAINT ORANGE (-3425 1400);
DISPLAY INVISIBLE (-3425 1400);
FORCEADD TAP..6
(-1475 3000);
FORCEPROP 3 LASTPIN (-1425 3000) SIG_NAME M_E_CS_N<7>
J 0
(-1415 3010);
DISPLAY 0.659574 (-1415 3010);
PAINT MONO (-1415 3010);
DISPLAY INVISIBLE (-1415 3010);
FORCEPROP 1 LASTPIN (-1425 3000) BN 7
J 0
(-1475 3010);
DISPLAY 0.617021 (-1475 3010);
PAINT PINK (-1475 3010);
FORCEPROP 2 LAST CDS_LIB mstr_standard
J 0
(-1475 3000);
DISPLAY 0.787234 (-1475 3000);
PAINT MONO (-1475 3000);
DISPLAY INVISIBLE (-1475 3000);
FORCEPROP 1 LAST BODY_TYPE PLUMBING
J 0
(-1475 2950);
DISPLAY 1.234043 (-1475 2950);
PAINT GREEN (-1475 2950);
DISPLAY INVISIBLE (-1475 2950);
FORCEPROP 1 LAST HDL_TAP TRUE
J 0
(-1150 2875);
DISPLAY 1.234043 (-1150 2875);
PAINT GREEN (-1150 2875);
DISPLAY INVISIBLE (-1150 2875);
FORCEPROP 1 LAST PATH I40
J 0
(-1477 3000);
DISPLAY 0.872340 (-1477 3000);
PAINT GREEN (-1477 3000);
DISPLAY INVISIBLE (-1477 3000);
FORCEADD TAP..6
(-1475 2950);
FORCEPROP 3 LASTPIN (-1425 2950) SIG_NAME M_E_CS_N<6>
J 0
(-1415 2960);
DISPLAY 0.659574 (-1415 2960);
PAINT MONO (-1415 2960);
DISPLAY INVISIBLE (-1415 2960);
FORCEPROP 1 LASTPIN (-1425 2950) BN 6
J 0
(-1475 2960);
DISPLAY 0.617021 (-1475 2960);
PAINT PINK (-1475 2960);
FORCEPROP 2 LAST CDS_LIB mstr_standard
J 0
(-1475 2950);
DISPLAY 0.787234 (-1475 2950);
PAINT MONO (-1475 2950);
DISPLAY INVISIBLE (-1475 2950);
FORCEPROP 1 LAST BODY_TYPE PLUMBING
J 0
(-1475 2900);
DISPLAY 1.234043 (-1475 2900);
PAINT GREEN (-1475 2900);
DISPLAY INVISIBLE (-1475 2900);
FORCEPROP 1 LAST HDL_TAP TRUE
J 0
(-1150 2825);
DISPLAY 1.234043 (-1150 2825);
PAINT GREEN (-1150 2825);
DISPLAY INVISIBLE (-1150 2825);
FORCEPROP 1 LAST PATH I41
J 0
(-1477 2950);
DISPLAY 0.872340 (-1477 2950);
PAINT GREEN (-1477 2950);
DISPLAY INVISIBLE (-1477 2950);
FORCEADD TAP..6
(-1875 3300);
FORCEPROP 3 LASTPIN (-1825 3300) SIG_NAME M_E_CLK_DP<3>
J 0
(-1815 3310);
DISPLAY 0.659574 (-1815 3310);
PAINT MONO (-1815 3310);
DISPLAY INVISIBLE (-1815 3310);
FORCEPROP 1 LASTPIN (-1825 3300) BN 3
J 0
(-1877 3308);
DISPLAY 0.617021 (-1877 3308);
PAINT PINK (-1877 3308);
FORCEPROP 2 LAST CDS_LIB mstr_standard
J 0
(-1875 3300);
PAINT MONO (-1875 3300);
DISPLAY INVISIBLE (-1875 3300);
FORCEPROP 1 LAST BODY_TYPE PLUMBING
J 0
(-1875 3250);
DISPLAY 1.234043 (-1875 3250);
PAINT GREEN (-1875 3250);
DISPLAY INVISIBLE (-1875 3250);
FORCEPROP 1 LAST HDL_TAP TRUE
J 0
(-1550 3175);
DISPLAY 1.234043 (-1550 3175);
PAINT GREEN (-1550 3175);
DISPLAY INVISIBLE (-1550 3175);
FORCEPROP 1 LAST PATH I42
J 0
(-1877 3300);
DISPLAY 0.872340 (-1877 3300);
PAINT GREEN (-1877 3300);
DISPLAY INVISIBLE (-1877 3300);
FORCEADD TAP..6
(-1875 3200);
FORCEPROP 3 LASTPIN (-1825 3200) SIG_NAME M_E_CLK_DP<2>
J 0
(-1815 3210);
DISPLAY 0.659574 (-1815 3210);
PAINT MONO (-1815 3210);
DISPLAY INVISIBLE (-1815 3210);
FORCEPROP 1 LASTPIN (-1825 3200) BN 2
J 0
(-1875 3210);
DISPLAY 0.617021 (-1875 3210);
PAINT PINK (-1875 3210);
FORCEPROP 2 LAST CDS_LIB mstr_standard
J 0
(-1875 3200);
DISPLAY 0.787234 (-1875 3200);
PAINT MONO (-1875 3200);
DISPLAY INVISIBLE (-1875 3200);
FORCEPROP 1 LAST BODY_TYPE PLUMBING
J 0
(-1875 3150);
DISPLAY 1.234043 (-1875 3150);
PAINT GREEN (-1875 3150);
DISPLAY INVISIBLE (-1875 3150);
FORCEPROP 1 LAST HDL_TAP TRUE
J 0
(-1550 3075);
DISPLAY 1.234043 (-1550 3075);
PAINT GREEN (-1550 3075);
DISPLAY INVISIBLE (-1550 3075);
FORCEPROP 1 LAST PATH I43
J 0
(-1877 3200);
DISPLAY 0.872340 (-1877 3200);
PAINT GREEN (-1877 3200);
DISPLAY INVISIBLE (-1877 3200);
FORCEADD TAP..6
(-1475 3400);
FORCEPROP 3 LASTPIN (-1425 3400) SIG_NAME M_E_BG<0>
J 0
(-1415 3410);
DISPLAY 0.659574 (-1415 3410);
PAINT MONO (-1415 3410);
DISPLAY INVISIBLE (-1415 3410);
FORCEPROP 1 LASTPIN (-1425 3400) BN 0
J 0
(-1475 3410);
DISPLAY 0.617021 (-1475 3410);
PAINT PINK (-1475 3410);
FORCEPROP 2 LAST CDS_LIB mstr_standard
J 0
(-1475 3400);
DISPLAY 0.787234 (-1475 3400);
PAINT MONO (-1475 3400);
DISPLAY INVISIBLE (-1475 3400);
FORCEPROP 1 LAST BODY_TYPE PLUMBING
J 0
(-1475 3350);
DISPLAY 1.234043 (-1475 3350);
PAINT GREEN (-1475 3350);
DISPLAY INVISIBLE (-1475 3350);
FORCEPROP 1 LAST HDL_TAP TRUE
J 0
(-1150 3275);
DISPLAY 1.234043 (-1150 3275);
PAINT GREEN (-1150 3275);
DISPLAY INVISIBLE (-1150 3275);
FORCEPROP 1 LAST PATH I44
J 0
(-1477 3400);
DISPLAY 0.872340 (-1477 3400);
PAINT GREEN (-1477 3400);
DISPLAY INVISIBLE (-1477 3400);
FORCEADD TAP..6
(-1475 3450);
FORCEPROP 3 LASTPIN (-1425 3450) SIG_NAME M_E_BG<1>
J 0
(-1415 3460);
DISPLAY 0.659574 (-1415 3460);
PAINT MONO (-1415 3460);
DISPLAY INVISIBLE (-1415 3460);
FORCEPROP 1 LASTPIN (-1425 3450) BN 1
J 0
(-1475 3460);
DISPLAY 0.617021 (-1475 3460);
PAINT PINK (-1475 3460);
FORCEPROP 2 LAST CDS_LIB mstr_standard
J 0
(-1475 3450);
DISPLAY 0.787234 (-1475 3450);
PAINT MONO (-1475 3450);
DISPLAY INVISIBLE (-1475 3450);
FORCEPROP 1 LAST BODY_TYPE PLUMBING
J 0
(-1475 3400);
DISPLAY 1.234043 (-1475 3400);
PAINT GREEN (-1475 3400);
DISPLAY INVISIBLE (-1475 3400);
FORCEPROP 1 LAST HDL_TAP TRUE
J 0
(-1150 3325);
DISPLAY 1.234043 (-1150 3325);
PAINT GREEN (-1150 3325);
DISPLAY INVISIBLE (-1150 3325);
FORCEPROP 1 LAST PATH I45
J 0
(-1477 3450);
DISPLAY 0.872340 (-1477 3450);
PAINT GREEN (-1477 3450);
DISPLAY INVISIBLE (-1477 3450);
FORCEADD TAP..6
(-1475 3500);
FORCEPROP 3 LASTPIN (-1425 3500) SIG_NAME M_E_BA<0>
J 0
(-1415 3510);
DISPLAY 0.659574 (-1415 3510);
PAINT MONO (-1415 3510);
DISPLAY INVISIBLE (-1415 3510);
FORCEPROP 1 LASTPIN (-1425 3500) BN 0
J 0
(-1475 3510);
DISPLAY 0.617021 (-1475 3510);
PAINT PINK (-1475 3510);
FORCEPROP 2 LAST CDS_LIB mstr_standard
J 0
(-1475 3500);
DISPLAY 0.787234 (-1475 3500);
PAINT MONO (-1475 3500);
DISPLAY INVISIBLE (-1475 3500);
FORCEPROP 1 LAST BODY_TYPE PLUMBING
J 0
(-1475 3450);
DISPLAY 1.234043 (-1475 3450);
PAINT GREEN (-1475 3450);
DISPLAY INVISIBLE (-1475 3450);
FORCEPROP 1 LAST HDL_TAP TRUE
J 0
(-1150 3375);
DISPLAY 1.234043 (-1150 3375);
PAINT GREEN (-1150 3375);
DISPLAY INVISIBLE (-1150 3375);
FORCEPROP 1 LAST PATH I46
J 0
(-1477 3500);
DISPLAY 0.872340 (-1477 3500);
PAINT GREEN (-1477 3500);
DISPLAY INVISIBLE (-1477 3500);
FORCEADD TAP..6
(-1475 3550);
FORCEPROP 3 LASTPIN (-1425 3550) SIG_NAME M_E_BA<1>
J 0
(-1415 3560);
DISPLAY 0.659574 (-1415 3560);
PAINT MONO (-1415 3560);
DISPLAY INVISIBLE (-1415 3560);
FORCEPROP 1 LASTPIN (-1425 3550) BN 1
J 0
(-1475 3560);
DISPLAY 0.617021 (-1475 3560);
PAINT PINK (-1475 3560);
FORCEPROP 2 LAST CDS_LIB mstr_standard
J 0
(-1475 3550);
DISPLAY 0.787234 (-1475 3550);
PAINT MONO (-1475 3550);
DISPLAY INVISIBLE (-1475 3550);
FORCEPROP 1 LAST BODY_TYPE PLUMBING
J 0
(-1475 3500);
DISPLAY 1.234043 (-1475 3500);
PAINT GREEN (-1475 3500);
DISPLAY INVISIBLE (-1475 3500);
FORCEPROP 1 LAST HDL_TAP TRUE
J 0
(-1150 3425);
DISPLAY 1.234043 (-1150 3425);
PAINT GREEN (-1150 3425);
DISPLAY INVISIBLE (-1150 3425);
FORCEPROP 1 LAST PATH I47
J 0
(-1477 3550);
DISPLAY 0.872340 (-1477 3550);
PAINT GREEN (-1477 3550);
DISPLAY INVISIBLE (-1477 3550);
FORCEADD TAP..6
(-1475 3650);
FORCEPROP 3 LASTPIN (-1425 3650) SIG_NAME M_E_MA<0>
J 0
(-1415 3660);
DISPLAY 0.659574 (-1415 3660);
PAINT MONO (-1415 3660);
DISPLAY INVISIBLE (-1415 3660);
FORCEPROP 1 LASTPIN (-1425 3650) BN 0
J 0
(-1475 3660);
DISPLAY 0.617021 (-1475 3660);
PAINT PINK (-1475 3660);
FORCEPROP 2 LAST CDS_LIB mstr_standard
J 2
(-1475 3650);
DISPLAY 0.787234 (-1475 3650);
PAINT MONO (-1475 3650);
DISPLAY INVISIBLE (-1475 3650);
FORCEPROP 1 LAST BODY_TYPE PLUMBING
J 0
(-1475 3600);
DISPLAY 1.234043 (-1475 3600);
PAINT GREEN (-1475 3600);
DISPLAY INVISIBLE (-1475 3600);
FORCEPROP 1 LAST HDL_TAP TRUE
J 0
(-1150 3525);
DISPLAY 1.234043 (-1150 3525);
PAINT GREEN (-1150 3525);
DISPLAY INVISIBLE (-1150 3525);
FORCEPROP 1 LAST PATH I48
J 0
(-1477 3650);
DISPLAY 0.872340 (-1477 3650);
PAINT GREEN (-1477 3650);
DISPLAY INVISIBLE (-1477 3650);
FORCEADD TAP..6
R 2
(25 1350);
FORCEPROP 3 LASTPIN (-25 1350) SIG_NAME M_E_DQ<0>
J 0
(-15 1360);
DISPLAY 0.659574 (-15 1360);
PAINT MONO (-15 1360);
DISPLAY INVISIBLE (-15 1360);
FORCEPROP 1 LASTPIN (-25 1350) BN 0
J 2
(25 1360);
DISPLAY 0.617021 (25 1360);
PAINT PINK (25 1360);
FORCEPROP 2 LAST CDS_LIB mstr_standard
J 2
(25 1350);
DISPLAY 0.787234 (25 1350);
PAINT MONO (25 1350);
DISPLAY INVISIBLE (25 1350);
FORCEPROP 1 LAST BODY_TYPE PLUMBING
J 2
(25 1300);
DISPLAY 1.234043 (25 1300);
PAINT GREEN (25 1300);
DISPLAY INVISIBLE (25 1300);
FORCEPROP 1 LAST HDL_TAP TRUE
J 2
(-300 1225);
DISPLAY 1.234043 (-300 1225);
PAINT GREEN (-300 1225);
DISPLAY INVISIBLE (-300 1225);
FORCEPROP 1 LAST PATH I49
J 2
(27 1350);
DISPLAY 0.872340 (27 1350);
PAINT GREEN (27 1350);
DISPLAY INVISIBLE (27 1350);
FORCEADD PVPP_DEF..1
(-3575 1850);
FORCEPROP 3 LASTPIN (-3575 1800) SIG_NAME PVPP_DEF\g
J 0
(-3565 1810);
DISPLAY 0.659574 (-3565 1810);
PAINT MONO (-3565 1810);
DISPLAY INVISIBLE (-3565 1810);
FORCEPROP 1 LAST VOLTAGE 2.5V
J 0
(-3620 1807);
DISPLAY 0.340426 (-3620 1807);
PAINT SKYBLUE (-3620 1807);
DISPLAY INVISIBLE (-3620 1807);
FORCEPROP 2 LAST CDS_LIB mstr_symbols
J 0
(-3575 1850);
PAINT ORANGE (-3575 1850);
DISPLAY INVISIBLE (-3575 1850);
FORCEPROP 1 LAST BODY_TYPE PLUMBING
J 0
(-3620 1807);
DISPLAY 0.340426 (-3620 1807);
PAINT GREEN (-3620 1807);
DISPLAY INVISIBLE (-3620 1807);
FORCEPROP 1 LAST PATH I5
J 0
(-3525 1875);
DISPLAY 0.872340 (-3525 1875);
PAINT AQUA (-3525 1875);
DISPLAY INVISIBLE (-3525 1875);
FORCEPROP 1 LAST HDL_POWER PVPP_DEF
J 1
(-3575 1900);
DISPLAY 0.872340 (-3575 1900);
PAINT GREEN (-3575 1900);
DISPLAY INVISIBLE (-3575 1900);
FORCEADD TAP..6
R 2
(25 1500);
FORCEPROP 3 LASTPIN (-25 1500) SIG_NAME M_E_DQ<3>
J 0
(-15 1510);
DISPLAY 0.659574 (-15 1510);
PAINT MONO (-15 1510);
DISPLAY INVISIBLE (-15 1510);
FORCEPROP 1 LASTPIN (-25 1500) BN 3
J 2
(25 1510);
DISPLAY 0.617021 (25 1510);
PAINT PINK (25 1510);
FORCEPROP 2 LAST CDS_LIB mstr_standard
J 2
(25 1500);
DISPLAY 0.787234 (25 1500);
PAINT MONO (25 1500);
DISPLAY INVISIBLE (25 1500);
FORCEPROP 1 LAST BODY_TYPE PLUMBING
J 2
(25 1450);
DISPLAY 1.234043 (25 1450);
PAINT GREEN (25 1450);
DISPLAY INVISIBLE (25 1450);
FORCEPROP 1 LAST HDL_TAP TRUE
J 2
(-300 1375);
DISPLAY 1.234043 (-300 1375);
PAINT GREEN (-300 1375);
DISPLAY INVISIBLE (-300 1375);
FORCEPROP 1 LAST PATH I50
J 2
(27 1500);
DISPLAY 0.872340 (27 1500);
PAINT GREEN (27 1500);
DISPLAY INVISIBLE (27 1500);
FORCEADD TAP..6
R 2
(25 1400);
FORCEPROP 3 LASTPIN (-25 1400) SIG_NAME M_E_DQ<1>
J 0
(-15 1410);
DISPLAY 0.659574 (-15 1410);
PAINT MONO (-15 1410);
DISPLAY INVISIBLE (-15 1410);
FORCEPROP 1 LASTPIN (-25 1400) BN 1
J 2
(25 1410);
DISPLAY 0.617021 (25 1410);
PAINT PINK (25 1410);
FORCEPROP 2 LAST CDS_LIB mstr_standard
J 2
(25 1400);
DISPLAY 0.787234 (25 1400);
PAINT MONO (25 1400);
DISPLAY INVISIBLE (25 1400);
FORCEPROP 1 LAST BODY_TYPE PLUMBING
J 2
(25 1350);
DISPLAY 1.234043 (25 1350);
PAINT GREEN (25 1350);
DISPLAY INVISIBLE (25 1350);
FORCEPROP 1 LAST HDL_TAP TRUE
J 2
(-300 1275);
DISPLAY 1.234043 (-300 1275);
PAINT GREEN (-300 1275);
DISPLAY INVISIBLE (-300 1275);
FORCEPROP 1 LAST PATH I51
J 2
(27 1400);
DISPLAY 0.872340 (27 1400);
PAINT GREEN (27 1400);
DISPLAY INVISIBLE (27 1400);
FORCEADD TAP..6
R 2
(25 1450);
FORCEPROP 3 LASTPIN (-25 1450) SIG_NAME M_E_DQ<2>
J 0
(-15 1460);
DISPLAY 0.659574 (-15 1460);
PAINT MONO (-15 1460);
DISPLAY INVISIBLE (-15 1460);
FORCEPROP 1 LASTPIN (-25 1450) BN 2
J 2
(25 1460);
DISPLAY 0.617021 (25 1460);
PAINT PINK (25 1460);
FORCEPROP 2 LAST CDS_LIB mstr_standard
J 2
(25 1450);
DISPLAY 0.787234 (25 1450);
PAINT MONO (25 1450);
DISPLAY INVISIBLE (25 1450);
FORCEPROP 1 LAST BODY_TYPE PLUMBING
J 2
(25 1400);
DISPLAY 1.234043 (25 1400);
PAINT GREEN (25 1400);
DISPLAY INVISIBLE (25 1400);
FORCEPROP 1 LAST HDL_TAP TRUE
J 2
(-300 1325);
DISPLAY 1.234043 (-300 1325);
PAINT GREEN (-300 1325);
DISPLAY INVISIBLE (-300 1325);
FORCEPROP 1 LAST PATH I52
J 2
(27 1450);
DISPLAY 0.872340 (27 1450);
PAINT GREEN (27 1450);
DISPLAY INVISIBLE (27 1450);
FORCEADD TAP..6
R 2
(25 1600);
FORCEPROP 3 LASTPIN (-25 1600) SIG_NAME M_E_DQ<5>
J 0
(-15 1610);
DISPLAY 0.659574 (-15 1610);
PAINT MONO (-15 1610);
DISPLAY INVISIBLE (-15 1610);
FORCEPROP 1 LASTPIN (-25 1600) BN 5
J 2
(25 1610);
DISPLAY 0.617021 (25 1610);
PAINT PINK (25 1610);
FORCEPROP 2 LAST CDS_LIB mstr_standard
J 2
(25 1600);
DISPLAY 0.787234 (25 1600);
PAINT MONO (25 1600);
DISPLAY INVISIBLE (25 1600);
FORCEPROP 1 LAST BODY_TYPE PLUMBING
J 2
(25 1550);
DISPLAY 1.234043 (25 1550);
PAINT GREEN (25 1550);
DISPLAY INVISIBLE (25 1550);
FORCEPROP 1 LAST HDL_TAP TRUE
J 2
(-300 1475);
DISPLAY 1.234043 (-300 1475);
PAINT GREEN (-300 1475);
DISPLAY INVISIBLE (-300 1475);
FORCEPROP 1 LAST PATH I53
J 2
(27 1600);
DISPLAY 0.872340 (27 1600);
PAINT GREEN (27 1600);
DISPLAY INVISIBLE (27 1600);
FORCEADD TAP..6
R 2
(25 1550);
FORCEPROP 3 LASTPIN (-25 1550) SIG_NAME M_E_DQ<4>
J 0
(-15 1560);
DISPLAY 0.659574 (-15 1560);
PAINT MONO (-15 1560);
DISPLAY INVISIBLE (-15 1560);
FORCEPROP 1 LASTPIN (-25 1550) BN 4
J 2
(25 1560);
DISPLAY 0.617021 (25 1560);
PAINT PINK (25 1560);
FORCEPROP 2 LAST CDS_LIB mstr_standard
J 2
(25 1550);
DISPLAY 0.787234 (25 1550);
PAINT MONO (25 1550);
DISPLAY INVISIBLE (25 1550);
FORCEPROP 1 LAST BODY_TYPE PLUMBING
J 2
(25 1500);
DISPLAY 1.234043 (25 1500);
PAINT GREEN (25 1500);
DISPLAY INVISIBLE (25 1500);
FORCEPROP 1 LAST HDL_TAP TRUE
J 2
(-300 1425);
DISPLAY 1.234043 (-300 1425);
PAINT GREEN (-300 1425);
DISPLAY INVISIBLE (-300 1425);
FORCEPROP 1 LAST PATH I54
J 2
(27 1550);
DISPLAY 0.872340 (27 1550);
PAINT GREEN (27 1550);
DISPLAY INVISIBLE (27 1550);
FORCEADD SCONN288_H44441003..4
(1475 1650);
FORCEPROP 1 LAST LOCATION J6L2
J 0
(1025 2750);
DISPLAY 0.617021 (1025 2750);
PAINT AQUA (1025 2750);
FORCEPROP 1 LAST PART_NUMBER H44441-003
J 0
(1025 600);
DISPLAY 0.617021 (1025 600);
PAINT BLUE (1025 600);
FORCEPROP 1 LAST MATERIAL SCONN
J 0
(1025 2700);
DISPLAY 0.617021 (1025 2700);
PAINT SKYBLUE (1025 2700);
FORCEPROP 2 LASTPIN (975 2200) $PN 77
J 2
(965 2210);
DISPLAY 0.617021 (965 2210);
PAINT ORANGE (965 2210);
FORCEPROP 2 LASTPIN (975 2150) $PN 221
J 2
(965 2160);
DISPLAY 0.617021 (965 2160);
PAINT ORANGE (965 2160);
FORCEPROP 2 LASTPIN (975 2500) $PN 142
J 2
(965 2510);
DISPLAY 0.617021 (965 2510);
PAINT ORANGE (965 2510);
FORCEPROP 2 LASTPIN (975 2450) $PN 143
J 2
(965 2460);
DISPLAY 0.617021 (965 2460);
PAINT ORANGE (965 2460);
FORCEPROP 2 LASTPIN (975 2400) $PN 288
J 2
(965 2410);
DISPLAY 0.617021 (965 2410);
PAINT ORANGE (965 2410);
FORCEPROP 2 LASTPIN (975 2350) $PN 286
J 2
(965 2360);
DISPLAY 0.617021 (965 2360);
PAINT ORANGE (965 2360);
FORCEPROP 2 LASTPIN (975 2300) $PN 287
J 2
(965 2310);
DISPLAY 0.617021 (965 2310);
PAINT ORANGE (965 2310);
FORCEPROP 2 LASTPIN (975 2050) $PN 59
J 2
(965 2060);
DISPLAY 0.617021 (965 2060);
PAINT ORANGE (965 2060);
FORCEPROP 2 LASTPIN (975 2000) $PN 61
J 2
(965 2010);
DISPLAY 0.617021 (965 2010);
PAINT ORANGE (965 2010);
FORCEPROP 2 LASTPIN (975 1950) $PN 64
J 2
(965 1960);
DISPLAY 0.617021 (965 1960);
PAINT ORANGE (965 1960);
FORCEPROP 2 LASTPIN (975 1900) $PN 67
J 2
(965 1910);
DISPLAY 0.617021 (965 1910);
PAINT ORANGE (965 1910);
FORCEPROP 2 LASTPIN (975 1850) $PN 70
J 2
(965 1860);
DISPLAY 0.617021 (965 1860);
PAINT ORANGE (965 1860);
FORCEPROP 2 LASTPIN (975 1800) $PN 73
J 2
(965 1810);
DISPLAY 0.617021 (965 1810);
PAINT ORANGE (965 1810);
FORCEPROP 2 LASTPIN (975 1750) $PN 76
J 2
(965 1760);
DISPLAY 0.617021 (965 1760);
PAINT ORANGE (965 1760);
FORCEPROP 2 LASTPIN (975 1700) $PN 80
J 2
(965 1710);
DISPLAY 0.617021 (965 1710);
PAINT ORANGE (965 1710);
FORCEPROP 2 LASTPIN (975 1650) $PN 83
J 2
(965 1660);
DISPLAY 0.617021 (965 1660);
PAINT ORANGE (965 1660);
FORCEPROP 2 LASTPIN (975 1600) $PN 85
J 2
(965 1610);
DISPLAY 0.617021 (965 1610);
PAINT ORANGE (965 1610);
FORCEPROP 2 LASTPIN (975 1550) $PN 88
J 2
(965 1560);
DISPLAY 0.617021 (965 1560);
PAINT ORANGE (965 1560);
FORCEPROP 2 LASTPIN (975 1500) $PN 90
J 2
(965 1510);
DISPLAY 0.617021 (965 1510);
PAINT ORANGE (965 1510);
FORCEPROP 2 LASTPIN (975 1450) $PN 92
J 2
(965 1460);
DISPLAY 0.617021 (965 1460);
PAINT ORANGE (965 1460);
FORCEPROP 2 LASTPIN (975 1400) $PN 204
J 2
(965 1410);
DISPLAY 0.617021 (965 1410);
PAINT ORANGE (965 1410);
FORCEPROP 2 LASTPIN (975 1350) $PN 206
J 2
(965 1360);
DISPLAY 0.617021 (965 1360);
PAINT ORANGE (965 1360);
FORCEPROP 2 LASTPIN (975 1300) $PN 209
J 2
(965 1310);
DISPLAY 0.617021 (965 1310);
PAINT ORANGE (965 1310);
FORCEPROP 2 LASTPIN (975 1250) $PN 212
J 2
(965 1260);
DISPLAY 0.617021 (965 1260);
PAINT ORANGE (965 1260);
FORCEPROP 2 LASTPIN (975 1200) $PN 215
J 2
(965 1210);
DISPLAY 0.617021 (965 1210);
PAINT ORANGE (965 1210);
FORCEPROP 2 LASTPIN (975 1150) $PN 217
J 2
(965 1160);
DISPLAY 0.617021 (965 1160);
PAINT ORANGE (965 1160);
FORCEPROP 2 LASTPIN (975 1100) $PN 220
J 2
(965 1110);
DISPLAY 0.617021 (965 1110);
PAINT ORANGE (965 1110);
FORCEPROP 2 LASTPIN (975 1050) $PN 223
J 2
(965 1060);
DISPLAY 0.617021 (965 1060);
PAINT ORANGE (965 1060);
FORCEPROP 2 LASTPIN (975 1000) $PN 226
J 2
(965 1010);
DISPLAY 0.617021 (965 1010);
PAINT ORANGE (965 1010);
FORCEPROP 2 LASTPIN (975 950) $PN 229
J 2
(965 960);
DISPLAY 0.617021 (965 960);
PAINT ORANGE (965 960);
FORCEPROP 2 LASTPIN (975 900) $PN 231
J 2
(965 910);
DISPLAY 0.617021 (965 910);
PAINT ORANGE (965 910);
FORCEPROP 2 LASTPIN (975 850) $PN 233
J 2
(965 860);
DISPLAY 0.617021 (965 860);
PAINT ORANGE (965 860);
FORCEPROP 2 LASTPIN (975 800) $PN 236
J 2
(965 810);
DISPLAY 0.617021 (965 810);
PAINT ORANGE (965 810);
FORCEPROP 2 LASTPIN (1975 2500) $PN 1
J 0
(1985 2510);
DISPLAY 0.617021 (1985 2510);
PAINT ORANGE (1985 2510);
FORCEPROP 2 LASTPIN (1975 2450) $PN 145
J 0
(1985 2460);
DISPLAY 0.617021 (1985 2460);
PAINT ORANGE (1985 2460);
FORCEPROP 1 LAST PACK_TYPE PIP
J 0
(1025 2800);
PAINT SKYBLUE (1025 2800);
DISPLAY INVISIBLE (1025 2800);
FORCEPROP 2 LAST BOM_COST MEM
J 0
(1025 2800);
PAINT MONO (1025 2800);
DISPLAY INVISIBLE (1025 2800);
FORCEPROP 2 LAST CDS_LIB mstr_sconn
J 0
(1475 1650);
PAINT ORANGE (1475 1650);
DISPLAY INVISIBLE (1475 1650);
FORCEPROP 2 LAST SEC_TYPE PIP
J 0
(1025 2800);
DISPLAY 1.021277 (1025 2800);
PAINT ORANGE (1025 2800);
DISPLAY INVISIBLE (1025 2800);
FORCEPROP 2 LAST SEC 4
J 0
(1025 2800);
DISPLAY 0.680851 (1025 2800);
PAINT MONO (1025 2800);
DISPLAY INVISIBLE (1025 2800);
FORCEPROP 2 LAST CDS_LOCATION J6L2
J 0
(1025 2750);
DISPLAY 0.617021 (1025 2750);
PAINT AQUA (1025 2750);
DISPLAY INVISIBLE (1025 2750);
FORCEPROP 1 LAST PATH I55
J 0
(1475 2700);
PAINT GREEN (1475 2700);
DISPLAY INVISIBLE (1475 2700);
FORCEPROP 2 LAST ROOM DDR4_CH_E
J 0
(1025 2800);
PAINT MONO (1025 2800);
DISPLAY INVISIBLE (1025 2800);
FORCEADD TAP..6
R 2
(25 1700);
FORCEPROP 3 LASTPIN (-25 1700) SIG_NAME M_E_DQ<7>
J 0
(-15 1710);
DISPLAY 0.659574 (-15 1710);
PAINT MONO (-15 1710);
DISPLAY INVISIBLE (-15 1710);
FORCEPROP 1 LASTPIN (-25 1700) BN 7
J 2
(25 1710);
DISPLAY 0.617021 (25 1710);
PAINT PINK (25 1710);
FORCEPROP 2 LAST CDS_LIB mstr_standard
J 2
(25 1700);
DISPLAY 0.787234 (25 1700);
PAINT MONO (25 1700);
DISPLAY INVISIBLE (25 1700);
FORCEPROP 1 LAST BODY_TYPE PLUMBING
J 2
(25 1650);
DISPLAY 1.234043 (25 1650);
PAINT GREEN (25 1650);
DISPLAY INVISIBLE (25 1650);
FORCEPROP 1 LAST HDL_TAP TRUE
J 2
(-300 1575);
DISPLAY 1.234043 (-300 1575);
PAINT GREEN (-300 1575);
DISPLAY INVISIBLE (-300 1575);
FORCEPROP 1 LAST PATH I56
J 2
(27 1700);
DISPLAY 0.872340 (27 1700);
PAINT GREEN (27 1700);
DISPLAY INVISIBLE (27 1700);
FORCEADD TAP..6
R 2
(25 1750);
FORCEPROP 3 LASTPIN (-25 1750) SIG_NAME M_E_DQ<8>
J 0
(-15 1760);
DISPLAY 0.659574 (-15 1760);
PAINT MONO (-15 1760);
DISPLAY INVISIBLE (-15 1760);
FORCEPROP 1 LASTPIN (-25 1750) BN 8
J 2
(25 1760);
DISPLAY 0.617021 (25 1760);
PAINT PINK (25 1760);
FORCEPROP 2 LAST CDS_LIB mstr_standard
J 2
(25 1750);
DISPLAY 0.787234 (25 1750);
PAINT MONO (25 1750);
DISPLAY INVISIBLE (25 1750);
FORCEPROP 1 LAST BODY_TYPE PLUMBING
J 2
(25 1700);
DISPLAY 1.234043 (25 1700);
PAINT GREEN (25 1700);
DISPLAY INVISIBLE (25 1700);
FORCEPROP 1 LAST HDL_TAP TRUE
J 2
(-300 1625);
DISPLAY 1.234043 (-300 1625);
PAINT GREEN (-300 1625);
DISPLAY INVISIBLE (-300 1625);
FORCEPROP 1 LAST PATH I57
J 2
(27 1750);
DISPLAY 0.872340 (27 1750);
PAINT GREEN (27 1750);
DISPLAY INVISIBLE (27 1750);
FORCEADD TAP..6
R 2
(25 1650);
FORCEPROP 3 LASTPIN (-25 1650) SIG_NAME M_E_DQ<6>
J 0
(-15 1660);
DISPLAY 0.659574 (-15 1660);
PAINT MONO (-15 1660);
DISPLAY INVISIBLE (-15 1660);
FORCEPROP 1 LASTPIN (-25 1650) BN 6
J 2
(25 1660);
DISPLAY 0.617021 (25 1660);
PAINT PINK (25 1660);
FORCEPROP 2 LAST CDS_LIB mstr_standard
J 2
(25 1650);
DISPLAY 0.787234 (25 1650);
PAINT MONO (25 1650);
DISPLAY INVISIBLE (25 1650);
FORCEPROP 1 LAST BODY_TYPE PLUMBING
J 2
(25 1600);
DISPLAY 1.234043 (25 1600);
PAINT GREEN (25 1600);
DISPLAY INVISIBLE (25 1600);
FORCEPROP 1 LAST HDL_TAP TRUE
J 2
(-300 1525);
DISPLAY 1.234043 (-300 1525);
PAINT GREEN (-300 1525);
DISPLAY INVISIBLE (-300 1525);
FORCEPROP 1 LAST PATH I58
J 2
(27 1650);
DISPLAY 0.872340 (27 1650);
PAINT GREEN (27 1650);
DISPLAY INVISIBLE (27 1650);
FORCEADD TAP..6
R 2
(25 1850);
FORCEPROP 3 LASTPIN (-25 1850) SIG_NAME M_E_DQ<10>
J 0
(-15 1860);
DISPLAY 0.659574 (-15 1860);
PAINT MONO (-15 1860);
DISPLAY INVISIBLE (-15 1860);
FORCEPROP 1 LASTPIN (-25 1850) BN 10
J 2
(25 1860);
DISPLAY 0.617021 (25 1860);
PAINT PINK (25 1860);
FORCEPROP 2 LAST CDS_LIB mstr_standard
J 2
(25 1850);
DISPLAY 0.787234 (25 1850);
PAINT MONO (25 1850);
DISPLAY INVISIBLE (25 1850);
FORCEPROP 1 LAST BODY_TYPE PLUMBING
J 2
(25 1800);
DISPLAY 1.234043 (25 1800);
PAINT GREEN (25 1800);
DISPLAY INVISIBLE (25 1800);
FORCEPROP 1 LAST HDL_TAP TRUE
J 2
(-300 1725);
DISPLAY 1.234043 (-300 1725);
PAINT GREEN (-300 1725);
DISPLAY INVISIBLE (-300 1725);
FORCEPROP 1 LAST PATH I59
J 2
(27 1850);
DISPLAY 0.872340 (27 1850);
PAINT GREEN (27 1850);
DISPLAY INVISIBLE (27 1850);
FORCEADD OFFPAGE..5
(-2450 2200);
FORCEPROP 2 LAST $XR0 43 
J 0
(-2674 2200);
DISPLAY 0.638298 (-2674 2200);
PAINT MONO (-2674 2200);
FORCEPROP 2 LAST $XR1 44 
J 0
(-2764 2200);
DISPLAY 0.638298 (-2764 2200);
PAINT MONO (-2764 2200);
FORCEPROP 2 LAST $XR2 45 
J 0
(-2854 2200);
DISPLAY 0.638298 (-2854 2200);
PAINT MONO (-2854 2200);
FORCEPROP 2 LAST $XR3 46 
J 0
(-2944 2200);
DISPLAY 0.638298 (-2944 2200);
PAINT MONO (-2944 2200);
FORCEPROP 2 LAST $XR4 47 
J 0
(-3034 2200);
DISPLAY 0.638298 (-3034 2200);
PAINT MONO (-3034 2200);
FORCEPROP 2 LAST $XR5 48 
J 0
(-3124 2200);
DISPLAY 0.638298 (-3124 2200);
PAINT MONO (-3124 2200);
FORCEPROP 2 LAST $XR6 49 
J 0
(-3214 2200);
DISPLAY 0.638298 (-3214 2200);
PAINT MONO (-3214 2200);
FORCEPROP 2 LAST $XR7 50 
J 0
(-3304 2200);
DISPLAY 0.638298 (-3304 2200);
PAINT MONO (-3304 2200);
FORCEPROP 2 LAST $XR8 51 
J 0
(-3394 2200);
DISPLAY 0.638298 (-3394 2200);
PAINT MONO (-3394 2200);
FORCEPROP 2 LAST $XR9 53 
J 0
(-3484 2200);
DISPLAY 0.638298 (-3484 2200);
PAINT MONO (-3484 2200);
FORCEPROP 2 LAST $XR10 54 
J 0
(-2674 2164);
DISPLAY 0.638298 (-2674 2164);
PAINT MONO (-2674 2164);
FORCEPROP 2 LAST $XR11 77 
J 0
(-2764 2164);
DISPLAY 0.638298 (-2764 2164);
PAINT MONO (-2764 2164);
FORCEPROP 2 LAST $XR12 78 
J 0
(-2854 2164);
DISPLAY 0.638298 (-2854 2164);
PAINT MONO (-2854 2164);
FORCEPROP 2 LAST $XR13 79 
J 0
(-2944 2164);
DISPLAY 0.638298 (-2944 2164);
PAINT MONO (-2944 2164);
FORCEPROP 2 LAST $XR14 80 
J 0
(-3034 2164);
DISPLAY 0.638298 (-3034 2164);
PAINT MONO (-3034 2164);
FORCEPROP 2 LAST $XR15 81 
J 0
(-3124 2164);
DISPLAY 0.638298 (-3124 2164);
PAINT MONO (-3124 2164);
FORCEPROP 2 LAST $XR16 82 
J 0
(-3214 2164);
DISPLAY 0.638298 (-3214 2164);
PAINT MONO (-3214 2164);
FORCEPROP 2 LAST $XR17 83 
J 0
(-3304 2164);
DISPLAY 0.638298 (-3304 2164);
PAINT MONO (-3304 2164);
FORCEPROP 2 LAST $XR18 84 
J 0
(-3394 2164);
DISPLAY 0.638298 (-3394 2164);
PAINT MONO (-3394 2164);
FORCEPROP 2 LAST $XR19 85 
J 0
(-3484 2164);
DISPLAY 0.638298 (-3484 2164);
PAINT MONO (-3484 2164);
FORCEPROP 2 LAST $XR20 86 
J 0
(-2674 2236);
DISPLAY 0.638298 (-2674 2236);
PAINT MONO (-2674 2236);
FORCEPROP 2 LAST $XR21 87 
J 0
(-2764 2236);
DISPLAY 0.638298 (-2764 2236);
PAINT MONO (-2764 2236);
FORCEPROP 2 LAST $XR22 88 
J 0
(-2854 2236);
DISPLAY 0.638298 (-2854 2236);
PAINT MONO (-2854 2236);
FORCEPROP 2 LAST $XR23 94 
J 0
(-2944 2236);
DISPLAY 0.638298 (-2944 2236);
PAINT MONO (-2944 2236);
FORCEPROP 2 LAST CDS_LIB mstr_standard
J 0
(-2450 2200);
DISPLAY 0.787234 (-2450 2200);
PAINT MONO (-2450 2200);
DISPLAY INVISIBLE (-2450 2200);
FORCEPROP 1 LAST OFFPAGE TRUE
J 0
(-2125 2075);
DISPLAY 1.404255 (-2125 2075);
PAINT GREEN (-2125 2075);
DISPLAY INVISIBLE (-2125 2075);
FORCEPROP 1 LAST COMMENT_BODY TRUE
J 0
(-2350 2125);
DISPLAY 1.404255 (-2350 2125);
PAINT GREEN (-2350 2125);
DISPLAY INVISIBLE (-2350 2125);
FORCEPROP 2 LAST PATH I6
J 0
(-2650 2250);
DISPLAY 1.021277 (-2650 2250);
PAINT ORANGE (-2650 2250);
DISPLAY INVISIBLE (-2650 2250);
FORCEADD TAP..6
R 2
(25 1800);
FORCEPROP 3 LASTPIN (-25 1800) SIG_NAME M_E_DQ<9>
J 0
(-15 1810);
DISPLAY 0.659574 (-15 1810);
PAINT MONO (-15 1810);
DISPLAY INVISIBLE (-15 1810);
FORCEPROP 1 LASTPIN (-25 1800) BN 9
J 2
(25 1810);
DISPLAY 0.617021 (25 1810);
PAINT PINK (25 1810);
FORCEPROP 2 LAST CDS_LIB mstr_standard
J 2
(25 1800);
DISPLAY 0.787234 (25 1800);
PAINT MONO (25 1800);
DISPLAY INVISIBLE (25 1800);
FORCEPROP 1 LAST BODY_TYPE PLUMBING
J 2
(25 1750);
DISPLAY 1.234043 (25 1750);
PAINT GREEN (25 1750);
DISPLAY INVISIBLE (25 1750);
FORCEPROP 1 LAST HDL_TAP TRUE
J 2
(-300 1675);
DISPLAY 1.234043 (-300 1675);
PAINT GREEN (-300 1675);
DISPLAY INVISIBLE (-300 1675);
FORCEPROP 1 LAST PATH I60
J 2
(27 1800);
DISPLAY 0.872340 (27 1800);
PAINT GREEN (27 1800);
DISPLAY INVISIBLE (27 1800);
FORCEADD TAP..6
R 2
(25 1900);
FORCEPROP 3 LASTPIN (-25 1900) SIG_NAME M_E_DQ<11>
J 0
(-15 1910);
DISPLAY 0.659574 (-15 1910);
PAINT MONO (-15 1910);
DISPLAY INVISIBLE (-15 1910);
FORCEPROP 1 LASTPIN (-25 1900) BN 11
J 2
(25 1910);
DISPLAY 0.617021 (25 1910);
PAINT PINK (25 1910);
FORCEPROP 2 LAST CDS_LIB mstr_standard
J 2
(25 1900);
DISPLAY 0.787234 (25 1900);
PAINT MONO (25 1900);
DISPLAY INVISIBLE (25 1900);
FORCEPROP 1 LAST BODY_TYPE PLUMBING
J 2
(25 1850);
DISPLAY 1.234043 (25 1850);
PAINT GREEN (25 1850);
DISPLAY INVISIBLE (25 1850);
FORCEPROP 1 LAST HDL_TAP TRUE
J 2
(-300 1775);
DISPLAY 1.234043 (-300 1775);
PAINT GREEN (-300 1775);
DISPLAY INVISIBLE (-300 1775);
FORCEPROP 1 LAST PATH I61
J 2
(27 1900);
DISPLAY 0.872340 (27 1900);
PAINT GREEN (27 1900);
DISPLAY INVISIBLE (27 1900);
FORCEADD TAP..6
R 2
(25 1950);
FORCEPROP 3 LASTPIN (-25 1950) SIG_NAME M_E_DQ<12>
J 0
(-15 1960);
DISPLAY 0.659574 (-15 1960);
PAINT MONO (-15 1960);
DISPLAY INVISIBLE (-15 1960);
FORCEPROP 1 LASTPIN (-25 1950) BN 12
J 2
(25 1960);
DISPLAY 0.617021 (25 1960);
PAINT PINK (25 1960);
FORCEPROP 2 LAST CDS_LIB mstr_standard
J 2
(25 1950);
DISPLAY 0.787234 (25 1950);
PAINT MONO (25 1950);
DISPLAY INVISIBLE (25 1950);
FORCEPROP 1 LAST BODY_TYPE PLUMBING
J 2
(25 1900);
DISPLAY 1.234043 (25 1900);
PAINT GREEN (25 1900);
DISPLAY INVISIBLE (25 1900);
FORCEPROP 1 LAST HDL_TAP TRUE
J 2
(-300 1825);
DISPLAY 1.234043 (-300 1825);
PAINT GREEN (-300 1825);
DISPLAY INVISIBLE (-300 1825);
FORCEPROP 1 LAST PATH I62
J 2
(27 1950);
DISPLAY 0.872340 (27 1950);
PAINT GREEN (27 1950);
DISPLAY INVISIBLE (27 1950);
FORCEADD TAP..6
R 2
(25 2000);
FORCEPROP 3 LASTPIN (-25 2000) SIG_NAME M_E_DQ<13>
J 0
(-15 2010);
DISPLAY 0.659574 (-15 2010);
PAINT MONO (-15 2010);
DISPLAY INVISIBLE (-15 2010);
FORCEPROP 1 LASTPIN (-25 2000) BN 13
J 2
(25 2010);
DISPLAY 0.617021 (25 2010);
PAINT PINK (25 2010);
FORCEPROP 2 LAST CDS_LIB mstr_standard
J 2
(25 2000);
DISPLAY 0.787234 (25 2000);
PAINT MONO (25 2000);
DISPLAY INVISIBLE (25 2000);
FORCEPROP 1 LAST BODY_TYPE PLUMBING
J 2
(25 1950);
DISPLAY 1.234043 (25 1950);
PAINT GREEN (25 1950);
DISPLAY INVISIBLE (25 1950);
FORCEPROP 1 LAST HDL_TAP TRUE
J 2
(-300 1875);
DISPLAY 1.234043 (-300 1875);
PAINT GREEN (-300 1875);
DISPLAY INVISIBLE (-300 1875);
FORCEPROP 1 LAST PATH I63
J 2
(27 2000);
DISPLAY 0.872340 (27 2000);
PAINT GREEN (27 2000);
DISPLAY INVISIBLE (27 2000);
FORCEADD TAP..6
R 2
(25 2150);
FORCEPROP 3 LASTPIN (-25 2150) SIG_NAME M_E_DQ<16>
J 0
(-15 2160);
DISPLAY 0.659574 (-15 2160);
PAINT MONO (-15 2160);
DISPLAY INVISIBLE (-15 2160);
FORCEPROP 1 LASTPIN (-25 2150) BN 16
J 2
(25 2160);
DISPLAY 0.617021 (25 2160);
PAINT PINK (25 2160);
FORCEPROP 2 LAST CDS_LIB mstr_standard
J 2
(25 2150);
DISPLAY 0.787234 (25 2150);
PAINT MONO (25 2150);
DISPLAY INVISIBLE (25 2150);
FORCEPROP 1 LAST BODY_TYPE PLUMBING
J 2
(25 2100);
DISPLAY 1.234043 (25 2100);
PAINT GREEN (25 2100);
DISPLAY INVISIBLE (25 2100);
FORCEPROP 1 LAST HDL_TAP TRUE
J 2
(-300 2025);
DISPLAY 1.234043 (-300 2025);
PAINT GREEN (-300 2025);
DISPLAY INVISIBLE (-300 2025);
FORCEPROP 1 LAST PATH I64
J 2
(27 2150);
DISPLAY 0.872340 (27 2150);
PAINT GREEN (27 2150);
DISPLAY INVISIBLE (27 2150);
FORCEADD TAP..6
R 2
(25 2100);
FORCEPROP 3 LASTPIN (-25 2100) SIG_NAME M_E_DQ<15>
J 0
(-15 2110);
DISPLAY 0.659574 (-15 2110);
PAINT MONO (-15 2110);
DISPLAY INVISIBLE (-15 2110);
FORCEPROP 1 LASTPIN (-25 2100) BN 15
J 2
(25 2110);
DISPLAY 0.617021 (25 2110);
PAINT PINK (25 2110);
FORCEPROP 2 LAST CDS_LIB mstr_standard
J 2
(25 2100);
DISPLAY 0.787234 (25 2100);
PAINT MONO (25 2100);
DISPLAY INVISIBLE (25 2100);
FORCEPROP 1 LAST BODY_TYPE PLUMBING
J 2
(25 2050);
DISPLAY 1.234043 (25 2050);
PAINT GREEN (25 2050);
DISPLAY INVISIBLE (25 2050);
FORCEPROP 1 LAST HDL_TAP TRUE
J 2
(-300 1975);
DISPLAY 1.234043 (-300 1975);
PAINT GREEN (-300 1975);
DISPLAY INVISIBLE (-300 1975);
FORCEPROP 1 LAST PATH I65
J 2
(27 2100);
DISPLAY 0.872340 (27 2100);
PAINT GREEN (27 2100);
DISPLAY INVISIBLE (27 2100);
FORCEADD TAP..6
R 2
(25 2050);
FORCEPROP 3 LASTPIN (-25 2050) SIG_NAME M_E_DQ<14>
J 0
(-15 2060);
DISPLAY 0.659574 (-15 2060);
PAINT MONO (-15 2060);
DISPLAY INVISIBLE (-15 2060);
FORCEPROP 1 LASTPIN (-25 2050) BN 14
J 2
(25 2060);
DISPLAY 0.617021 (25 2060);
PAINT PINK (25 2060);
FORCEPROP 2 LAST CDS_LIB mstr_standard
J 2
(25 2050);
DISPLAY 0.787234 (25 2050);
PAINT MONO (25 2050);
DISPLAY INVISIBLE (25 2050);
FORCEPROP 1 LAST BODY_TYPE PLUMBING
J 2
(25 2000);
DISPLAY 1.234043 (25 2000);
PAINT GREEN (25 2000);
DISPLAY INVISIBLE (25 2000);
FORCEPROP 1 LAST HDL_TAP TRUE
J 2
(-300 1925);
DISPLAY 1.234043 (-300 1925);
PAINT GREEN (-300 1925);
DISPLAY INVISIBLE (-300 1925);
FORCEPROP 1 LAST PATH I66
J 2
(27 2050);
DISPLAY 0.872340 (27 2050);
PAINT GREEN (27 2050);
DISPLAY INVISIBLE (27 2050);
FORCEADD TAP..6
R 2
(25 2250);
FORCEPROP 3 LASTPIN (-25 2250) SIG_NAME M_E_DQ<18>
J 0
(-15 2260);
DISPLAY 0.659574 (-15 2260);
PAINT MONO (-15 2260);
DISPLAY INVISIBLE (-15 2260);
FORCEPROP 1 LASTPIN (-25 2250) BN 18
J 2
(25 2260);
DISPLAY 0.617021 (25 2260);
PAINT PINK (25 2260);
FORCEPROP 2 LAST CDS_LIB mstr_standard
J 2
(25 2250);
DISPLAY 0.787234 (25 2250);
PAINT MONO (25 2250);
DISPLAY INVISIBLE (25 2250);
FORCEPROP 1 LAST BODY_TYPE PLUMBING
J 2
(25 2200);
DISPLAY 1.234043 (25 2200);
PAINT GREEN (25 2200);
DISPLAY INVISIBLE (25 2200);
FORCEPROP 1 LAST HDL_TAP TRUE
J 2
(-300 2125);
DISPLAY 1.234043 (-300 2125);
PAINT GREEN (-300 2125);
DISPLAY INVISIBLE (-300 2125);
FORCEPROP 1 LAST PATH I67
J 2
(27 2250);
DISPLAY 0.872340 (27 2250);
PAINT GREEN (27 2250);
DISPLAY INVISIBLE (27 2250);
FORCEADD TAP..6
R 2
(25 2200);
FORCEPROP 3 LASTPIN (-25 2200) SIG_NAME M_E_DQ<17>
J 0
(-15 2210);
DISPLAY 0.659574 (-15 2210);
PAINT MONO (-15 2210);
DISPLAY INVISIBLE (-15 2210);
FORCEPROP 1 LASTPIN (-25 2200) BN 17
J 2
(25 2210);
DISPLAY 0.617021 (25 2210);
PAINT PINK (25 2210);
FORCEPROP 2 LAST CDS_LIB mstr_standard
J 2
(25 2200);
DISPLAY 0.787234 (25 2200);
PAINT MONO (25 2200);
DISPLAY INVISIBLE (25 2200);
FORCEPROP 1 LAST BODY_TYPE PLUMBING
J 2
(25 2150);
DISPLAY 1.234043 (25 2150);
PAINT GREEN (25 2150);
DISPLAY INVISIBLE (25 2150);
FORCEPROP 1 LAST HDL_TAP TRUE
J 2
(-300 2075);
DISPLAY 1.234043 (-300 2075);
PAINT GREEN (-300 2075);
DISPLAY INVISIBLE (-300 2075);
FORCEPROP 1 LAST PATH I68
J 2
(27 2200);
DISPLAY 0.872340 (27 2200);
PAINT GREEN (27 2200);
DISPLAY INVISIBLE (27 2200);
FORCEADD TAP..6
R 2
(25 2400);
FORCEPROP 3 LASTPIN (-25 2400) SIG_NAME M_E_DQ<21>
J 0
(-15 2410);
DISPLAY 0.659574 (-15 2410);
PAINT MONO (-15 2410);
DISPLAY INVISIBLE (-15 2410);
FORCEPROP 1 LASTPIN (-25 2400) BN 21
J 2
(25 2410);
DISPLAY 0.617021 (25 2410);
PAINT PINK (25 2410);
FORCEPROP 2 LAST CDS_LIB mstr_standard
J 2
(25 2400);
DISPLAY 0.787234 (25 2400);
PAINT MONO (25 2400);
DISPLAY INVISIBLE (25 2400);
FORCEPROP 1 LAST BODY_TYPE PLUMBING
J 2
(25 2350);
DISPLAY 1.234043 (25 2350);
PAINT GREEN (25 2350);
DISPLAY INVISIBLE (25 2350);
FORCEPROP 1 LAST HDL_TAP TRUE
J 2
(-300 2275);
DISPLAY 1.234043 (-300 2275);
PAINT GREEN (-300 2275);
DISPLAY INVISIBLE (-300 2275);
FORCEPROP 1 LAST PATH I69
J 2
(27 2400);
DISPLAY 0.872340 (27 2400);
PAINT GREEN (27 2400);
DISPLAY INVISIBLE (27 2400);
FORCEADD OFFPAGE..1
(-2575 3400);
FORCEPROP 2 LAST $XR0 27 
J 0
(-2796 3400);
DISPLAY 0.638298 (-2796 3400);
PAINT MONO (-2796 3400);
FORCEPROP 2 LAST $XR1 51 
J 0
(-2886 3400);
DISPLAY 0.638298 (-2886 3400);
PAINT MONO (-2886 3400);
FORCEPROP 2 LAST CDS_LIB mstr_standard
J 0
(-2575 3400);
DISPLAY 0.787234 (-2575 3400);
PAINT MONO (-2575 3400);
DISPLAY INVISIBLE (-2575 3400);
FORCEPROP 1 LAST OFFPAGE TRUE
J 0
(-2250 3275);
DISPLAY 0.936170 (-2250 3275);
PAINT GREEN (-2250 3275);
DISPLAY INVISIBLE (-2250 3275);
FORCEPROP 1 LAST COMMENT_BODY TRUE
J 0
(-2450 3300);
DISPLAY 0.936170 (-2450 3300);
PAINT GREEN (-2450 3300);
DISPLAY INVISIBLE (-2450 3300);
FORCEPROP 2 LAST PATH I7
J 0
(-2825 3450);
DISPLAY 1.021277 (-2825 3450);
PAINT ORANGE (-2825 3450);
DISPLAY INVISIBLE (-2825 3450);
FORCEADD TAP..6
R 2
(25 2350);
FORCEPROP 3 LASTPIN (-25 2350) SIG_NAME M_E_DQ<20>
J 0
(-15 2360);
DISPLAY 0.659574 (-15 2360);
PAINT MONO (-15 2360);
DISPLAY INVISIBLE (-15 2360);
FORCEPROP 1 LASTPIN (-25 2350) BN 20
J 2
(25 2360);
DISPLAY 0.617021 (25 2360);
PAINT PINK (25 2360);
FORCEPROP 2 LAST CDS_LIB mstr_standard
J 2
(25 2350);
DISPLAY 0.787234 (25 2350);
PAINT MONO (25 2350);
DISPLAY INVISIBLE (25 2350);
FORCEPROP 1 LAST BODY_TYPE PLUMBING
J 2
(25 2300);
DISPLAY 1.234043 (25 2300);
PAINT GREEN (25 2300);
DISPLAY INVISIBLE (25 2300);
FORCEPROP 1 LAST HDL_TAP TRUE
J 2
(-300 2225);
DISPLAY 1.234043 (-300 2225);
PAINT GREEN (-300 2225);
DISPLAY INVISIBLE (-300 2225);
FORCEPROP 1 LAST PATH I70
J 2
(27 2350);
DISPLAY 0.872340 (27 2350);
PAINT GREEN (27 2350);
DISPLAY INVISIBLE (27 2350);
FORCEADD TAP..6
R 2
(25 2300);
FORCEPROP 3 LASTPIN (-25 2300) SIG_NAME M_E_DQ<19>
J 0
(-15 2310);
DISPLAY 0.659574 (-15 2310);
PAINT MONO (-15 2310);
DISPLAY INVISIBLE (-15 2310);
FORCEPROP 1 LASTPIN (-25 2300) BN 19
J 2
(25 2310);
DISPLAY 0.617021 (25 2310);
PAINT PINK (25 2310);
FORCEPROP 2 LAST CDS_LIB mstr_standard
J 2
(25 2300);
DISPLAY 0.787234 (25 2300);
PAINT MONO (25 2300);
DISPLAY INVISIBLE (25 2300);
FORCEPROP 1 LAST BODY_TYPE PLUMBING
J 2
(25 2250);
DISPLAY 1.234043 (25 2250);
PAINT GREEN (25 2250);
DISPLAY INVISIBLE (25 2250);
FORCEPROP 1 LAST HDL_TAP TRUE
J 2
(-300 2175);
DISPLAY 1.234043 (-300 2175);
PAINT GREEN (-300 2175);
DISPLAY INVISIBLE (-300 2175);
FORCEPROP 1 LAST PATH I71
J 2
(27 2300);
DISPLAY 0.872340 (27 2300);
PAINT GREEN (27 2300);
DISPLAY INVISIBLE (27 2300);
FORCEADD TAP..6
R 2
(25 2450);
FORCEPROP 3 LASTPIN (-25 2450) SIG_NAME M_E_DQ<22>
J 0
(-15 2460);
DISPLAY 0.659574 (-15 2460);
PAINT MONO (-15 2460);
DISPLAY INVISIBLE (-15 2460);
FORCEPROP 1 LASTPIN (-25 2450) BN 22
J 2
(25 2460);
DISPLAY 0.617021 (25 2460);
PAINT PINK (25 2460);
FORCEPROP 2 LAST CDS_LIB mstr_standard
J 2
(25 2450);
DISPLAY 0.787234 (25 2450);
PAINT MONO (25 2450);
DISPLAY INVISIBLE (25 2450);
FORCEPROP 1 LAST BODY_TYPE PLUMBING
J 2
(25 2400);
DISPLAY 1.234043 (25 2400);
PAINT GREEN (25 2400);
DISPLAY INVISIBLE (25 2400);
FORCEPROP 1 LAST HDL_TAP TRUE
J 2
(-300 2325);
DISPLAY 1.234043 (-300 2325);
PAINT GREEN (-300 2325);
DISPLAY INVISIBLE (-300 2325);
FORCEPROP 1 LAST PATH I72
J 2
(27 2450);
DISPLAY 0.872340 (27 2450);
PAINT GREEN (27 2450);
DISPLAY INVISIBLE (27 2450);
FORCEADD TAP..6
R 2
(25 2500);
FORCEPROP 3 LASTPIN (-25 2500) SIG_NAME M_E_DQ<23>
J 0
(-15 2510);
DISPLAY 0.659574 (-15 2510);
PAINT MONO (-15 2510);
DISPLAY INVISIBLE (-15 2510);
FORCEPROP 1 LASTPIN (-25 2500) BN 23
J 2
(25 2510);
DISPLAY 0.617021 (25 2510);
PAINT PINK (25 2510);
FORCEPROP 2 LAST CDS_LIB mstr_standard
J 2
(25 2500);
DISPLAY 0.787234 (25 2500);
PAINT MONO (25 2500);
DISPLAY INVISIBLE (25 2500);
FORCEPROP 1 LAST BODY_TYPE PLUMBING
J 2
(25 2450);
DISPLAY 1.234043 (25 2450);
PAINT GREEN (25 2450);
DISPLAY INVISIBLE (25 2450);
FORCEPROP 1 LAST HDL_TAP TRUE
J 2
(-300 2375);
DISPLAY 1.234043 (-300 2375);
PAINT GREEN (-300 2375);
DISPLAY INVISIBLE (-300 2375);
FORCEPROP 1 LAST PATH I73
J 2
(27 2500);
DISPLAY 0.872340 (27 2500);
PAINT GREEN (27 2500);
DISPLAY INVISIBLE (27 2500);
FORCEADD TAP..6
R 2
(25 2650);
FORCEPROP 3 LASTPIN (-25 2650) SIG_NAME M_E_DQ<26>
J 0
(-15 2660);
DISPLAY 0.659574 (-15 2660);
PAINT MONO (-15 2660);
DISPLAY INVISIBLE (-15 2660);
FORCEPROP 1 LASTPIN (-25 2650) BN 26
J 2
(25 2660);
DISPLAY 0.617021 (25 2660);
PAINT PINK (25 2660);
FORCEPROP 2 LAST CDS_LIB mstr_standard
J 2
(25 2650);
DISPLAY 0.787234 (25 2650);
PAINT MONO (25 2650);
DISPLAY INVISIBLE (25 2650);
FORCEPROP 1 LAST BODY_TYPE PLUMBING
J 2
(25 2600);
DISPLAY 1.234043 (25 2600);
PAINT GREEN (25 2600);
DISPLAY INVISIBLE (25 2600);
FORCEPROP 1 LAST HDL_TAP TRUE
J 2
(-300 2525);
DISPLAY 1.234043 (-300 2525);
PAINT GREEN (-300 2525);
DISPLAY INVISIBLE (-300 2525);
FORCEPROP 1 LAST PATH I74
J 2
(27 2650);
DISPLAY 0.872340 (27 2650);
PAINT GREEN (27 2650);
DISPLAY INVISIBLE (27 2650);
FORCEADD TAP..6
R 2
(25 2550);
FORCEPROP 3 LASTPIN (-25 2550) SIG_NAME M_E_DQ<24>
J 0
(-15 2560);
DISPLAY 0.659574 (-15 2560);
PAINT MONO (-15 2560);
DISPLAY INVISIBLE (-15 2560);
FORCEPROP 1 LASTPIN (-25 2550) BN 24
J 2
(25 2560);
DISPLAY 0.617021 (25 2560);
PAINT PINK (25 2560);
FORCEPROP 2 LAST CDS_LIB mstr_standard
J 2
(25 2550);
DISPLAY 0.787234 (25 2550);
PAINT MONO (25 2550);
DISPLAY INVISIBLE (25 2550);
FORCEPROP 1 LAST BODY_TYPE PLUMBING
J 2
(25 2500);
DISPLAY 1.234043 (25 2500);
PAINT GREEN (25 2500);
DISPLAY INVISIBLE (25 2500);
FORCEPROP 1 LAST HDL_TAP TRUE
J 2
(-300 2425);
DISPLAY 1.234043 (-300 2425);
PAINT GREEN (-300 2425);
DISPLAY INVISIBLE (-300 2425);
FORCEPROP 1 LAST PATH I75
J 2
(27 2550);
DISPLAY 0.872340 (27 2550);
PAINT GREEN (27 2550);
DISPLAY INVISIBLE (27 2550);
FORCEADD TAP..6
R 2
(25 2600);
FORCEPROP 3 LASTPIN (-25 2600) SIG_NAME M_E_DQ<25>
J 0
(-15 2610);
DISPLAY 0.659574 (-15 2610);
PAINT MONO (-15 2610);
DISPLAY INVISIBLE (-15 2610);
FORCEPROP 1 LASTPIN (-25 2600) BN 25
J 2
(25 2610);
DISPLAY 0.617021 (25 2610);
PAINT PINK (25 2610);
FORCEPROP 2 LAST CDS_LIB mstr_standard
J 2
(25 2600);
DISPLAY 0.787234 (25 2600);
PAINT MONO (25 2600);
DISPLAY INVISIBLE (25 2600);
FORCEPROP 1 LAST BODY_TYPE PLUMBING
J 2
(25 2550);
DISPLAY 1.234043 (25 2550);
PAINT GREEN (25 2550);
DISPLAY INVISIBLE (25 2550);
FORCEPROP 1 LAST HDL_TAP TRUE
J 2
(-300 2475);
DISPLAY 1.234043 (-300 2475);
PAINT GREEN (-300 2475);
DISPLAY INVISIBLE (-300 2475);
FORCEPROP 1 LAST PATH I76
J 2
(27 2600);
DISPLAY 0.872340 (27 2600);
PAINT GREEN (27 2600);
DISPLAY INVISIBLE (27 2600);
FORCEADD PVDDQ_DEF..1
(375 2200);
FORCEPROP 3 LASTPIN (375 2150) SIG_NAME PVDDQ_DEF\g
J 0
(385 2160);
DISPLAY 0.659574 (385 2160);
PAINT MONO (385 2160);
DISPLAY INVISIBLE (385 2160);
FORCEPROP 1 LAST VOLTAGE 1.2V
J 0
(330 2157);
DISPLAY 0.340426 (330 2157);
PAINT SKYBLUE (330 2157);
DISPLAY INVISIBLE (330 2157);
FORCEPROP 2 LAST CDS_LIB mstr_symbols
J 0
(375 2200);
PAINT ORANGE (375 2200);
DISPLAY INVISIBLE (375 2200);
FORCEPROP 1 LAST BODY_TYPE PLUMBING
J 0
(330 2157);
DISPLAY 0.340426 (330 2157);
PAINT GREEN (330 2157);
DISPLAY INVISIBLE (330 2157);
FORCEPROP 1 LAST PATH I77
J 0
(425 2225);
DISPLAY 0.872340 (425 2225);
PAINT AQUA (425 2225);
DISPLAY INVISIBLE (425 2225);
FORCEPROP 1 LAST HDL_POWER PVDDQ_DEF
J 1
(375 2250);
DISPLAY 0.872340 (375 2250);
PAINT GREEN (375 2250);
DISPLAY INVISIBLE (375 2250);
FORCEADD TAP..6
R 2
(25 2700);
FORCEPROP 3 LASTPIN (-25 2700) SIG_NAME M_E_DQ<27>
J 0
(-15 2710);
DISPLAY 0.659574 (-15 2710);
PAINT MONO (-15 2710);
DISPLAY INVISIBLE (-15 2710);
FORCEPROP 1 LASTPIN (-25 2700) BN 27
J 2
(25 2710);
DISPLAY 0.617021 (25 2710);
PAINT PINK (25 2710);
FORCEPROP 2 LAST CDS_LIB mstr_standard
J 2
(25 2700);
DISPLAY 0.787234 (25 2700);
PAINT MONO (25 2700);
DISPLAY INVISIBLE (25 2700);
FORCEPROP 1 LAST BODY_TYPE PLUMBING
J 2
(25 2650);
DISPLAY 1.234043 (25 2650);
PAINT GREEN (25 2650);
DISPLAY INVISIBLE (25 2650);
FORCEPROP 1 LAST HDL_TAP TRUE
J 2
(-300 2575);
DISPLAY 1.234043 (-300 2575);
PAINT GREEN (-300 2575);
DISPLAY INVISIBLE (-300 2575);
FORCEPROP 1 LAST PATH I78
J 2
(27 2700);
DISPLAY 0.872340 (27 2700);
PAINT GREEN (27 2700);
DISPLAY INVISIBLE (27 2700);
FORCEADD TAP..6
R 2
(25 2750);
FORCEPROP 3 LASTPIN (-25 2750) SIG_NAME M_E_DQ<28>
J 0
(-15 2760);
DISPLAY 0.659574 (-15 2760);
PAINT MONO (-15 2760);
DISPLAY INVISIBLE (-15 2760);
FORCEPROP 1 LASTPIN (-25 2750) BN 28
J 2
(25 2760);
DISPLAY 0.617021 (25 2760);
PAINT PINK (25 2760);
FORCEPROP 2 LAST CDS_LIB mstr_standard
J 2
(25 2750);
DISPLAY 0.787234 (25 2750);
PAINT MONO (25 2750);
DISPLAY INVISIBLE (25 2750);
FORCEPROP 1 LAST BODY_TYPE PLUMBING
J 2
(25 2700);
DISPLAY 1.234043 (25 2700);
PAINT GREEN (25 2700);
DISPLAY INVISIBLE (25 2700);
FORCEPROP 1 LAST HDL_TAP TRUE
J 2
(-300 2625);
DISPLAY 1.234043 (-300 2625);
PAINT GREEN (-300 2625);
DISPLAY INVISIBLE (-300 2625);
FORCEPROP 1 LAST PATH I79
J 2
(27 2750);
DISPLAY 0.872340 (27 2750);
PAINT GREEN (27 2750);
DISPLAY INVISIBLE (27 2750);
FORCEADD OFFPAGE..1
(-2575 3350);
FORCEPROP 2 LAST $XR0 27 
J 0
(-2796 3350);
DISPLAY 0.638298 (-2796 3350);
PAINT MONO (-2796 3350);
FORCEPROP 2 LAST $XR1 51 
J 0
(-2886 3350);
DISPLAY 0.638298 (-2886 3350);
PAINT MONO (-2886 3350);
FORCEPROP 2 LAST CDS_LIB mstr_standard
J 0
(-2575 3350);
DISPLAY 0.787234 (-2575 3350);
PAINT MONO (-2575 3350);
DISPLAY INVISIBLE (-2575 3350);
FORCEPROP 1 LAST OFFPAGE TRUE
J 0
(-2250 3225);
DISPLAY 0.936170 (-2250 3225);
PAINT GREEN (-2250 3225);
DISPLAY INVISIBLE (-2250 3225);
FORCEPROP 1 LAST COMMENT_BODY TRUE
J 0
(-2450 3250);
DISPLAY 0.936170 (-2450 3250);
PAINT GREEN (-2450 3250);
DISPLAY INVISIBLE (-2450 3250);
FORCEPROP 2 LAST PATH I8
J 0
(-2825 3400);
DISPLAY 1.021277 (-2825 3400);
PAINT ORANGE (-2825 3400);
DISPLAY INVISIBLE (-2825 3400);
FORCEADD TAP..6
R 2
(25 2800);
FORCEPROP 3 LASTPIN (-25 2800) SIG_NAME M_E_DQ<29>
J 0
(-15 2810);
DISPLAY 0.659574 (-15 2810);
PAINT MONO (-15 2810);
DISPLAY INVISIBLE (-15 2810);
FORCEPROP 1 LASTPIN (-25 2800) BN 29
J 2
(25 2810);
DISPLAY 0.617021 (25 2810);
PAINT PINK (25 2810);
FORCEPROP 2 LAST CDS_LIB mstr_standard
J 2
(25 2800);
DISPLAY 0.787234 (25 2800);
PAINT MONO (25 2800);
DISPLAY INVISIBLE (25 2800);
FORCEPROP 1 LAST BODY_TYPE PLUMBING
J 2
(25 2750);
DISPLAY 1.234043 (25 2750);
PAINT GREEN (25 2750);
DISPLAY INVISIBLE (25 2750);
FORCEPROP 1 LAST HDL_TAP TRUE
J 2
(-300 2675);
DISPLAY 1.234043 (-300 2675);
PAINT GREEN (-300 2675);
DISPLAY INVISIBLE (-300 2675);
FORCEPROP 1 LAST PATH I80
J 2
(27 2800);
DISPLAY 0.872340 (27 2800);
PAINT GREEN (27 2800);
DISPLAY INVISIBLE (27 2800);
FORCEADD TAP..6
R 2
(25 2900);
FORCEPROP 3 LASTPIN (-25 2900) SIG_NAME M_E_DQ<31>
J 0
(-15 2910);
DISPLAY 0.659574 (-15 2910);
PAINT MONO (-15 2910);
DISPLAY INVISIBLE (-15 2910);
FORCEPROP 1 LASTPIN (-25 2900) BN 31
J 2
(25 2910);
DISPLAY 0.617021 (25 2910);
PAINT PINK (25 2910);
FORCEPROP 2 LAST CDS_LIB mstr_standard
J 2
(25 2900);
DISPLAY 0.787234 (25 2900);
PAINT MONO (25 2900);
DISPLAY INVISIBLE (25 2900);
FORCEPROP 1 LAST BODY_TYPE PLUMBING
J 2
(25 2850);
DISPLAY 1.234043 (25 2850);
PAINT GREEN (25 2850);
DISPLAY INVISIBLE (25 2850);
FORCEPROP 1 LAST HDL_TAP TRUE
J 2
(-300 2775);
DISPLAY 1.234043 (-300 2775);
PAINT GREEN (-300 2775);
DISPLAY INVISIBLE (-300 2775);
FORCEPROP 1 LAST PATH I81
J 2
(27 2900);
DISPLAY 0.872340 (27 2900);
PAINT GREEN (27 2900);
DISPLAY INVISIBLE (27 2900);
FORCEADD TAP..6
R 2
(25 2850);
FORCEPROP 3 LASTPIN (-25 2850) SIG_NAME M_E_DQ<30>
J 0
(-15 2860);
DISPLAY 0.659574 (-15 2860);
PAINT MONO (-15 2860);
DISPLAY INVISIBLE (-15 2860);
FORCEPROP 1 LASTPIN (-25 2850) BN 30
J 2
(25 2860);
DISPLAY 0.617021 (25 2860);
PAINT PINK (25 2860);
FORCEPROP 2 LAST CDS_LIB mstr_standard
J 2
(25 2850);
DISPLAY 0.787234 (25 2850);
PAINT MONO (25 2850);
DISPLAY INVISIBLE (25 2850);
FORCEPROP 1 LAST BODY_TYPE PLUMBING
J 2
(25 2800);
DISPLAY 1.234043 (25 2800);
PAINT GREEN (25 2800);
DISPLAY INVISIBLE (25 2800);
FORCEPROP 1 LAST HDL_TAP TRUE
J 2
(-300 2725);
DISPLAY 1.234043 (-300 2725);
PAINT GREEN (-300 2725);
DISPLAY INVISIBLE (-300 2725);
FORCEPROP 1 LAST PATH I82
J 2
(27 2850);
DISPLAY 0.872340 (27 2850);
PAINT GREEN (27 2850);
DISPLAY INVISIBLE (27 2850);
FORCEADD TAP..6
R 2
(25 3050);
FORCEPROP 3 LASTPIN (-25 3050) SIG_NAME M_E_DQ<34>
J 0
(-15 3060);
DISPLAY 0.659574 (-15 3060);
PAINT MONO (-15 3060);
DISPLAY INVISIBLE (-15 3060);
FORCEPROP 1 LASTPIN (-25 3050) BN 34
J 2
(25 3060);
DISPLAY 0.617021 (25 3060);
PAINT PINK (25 3060);
FORCEPROP 2 LAST CDS_LIB mstr_standard
J 2
(25 3050);
DISPLAY 0.787234 (25 3050);
PAINT MONO (25 3050);
DISPLAY INVISIBLE (25 3050);
FORCEPROP 1 LAST BODY_TYPE PLUMBING
J 2
(25 3000);
DISPLAY 1.234043 (25 3000);
PAINT GREEN (25 3000);
DISPLAY INVISIBLE (25 3000);
FORCEPROP 1 LAST HDL_TAP TRUE
J 2
(-300 2925);
DISPLAY 1.234043 (-300 2925);
PAINT GREEN (-300 2925);
DISPLAY INVISIBLE (-300 2925);
FORCEPROP 1 LAST PATH I83
J 2
(27 3050);
DISPLAY 0.872340 (27 3050);
PAINT GREEN (27 3050);
DISPLAY INVISIBLE (27 3050);
FORCEADD TAP..6
R 2
(25 3000);
FORCEPROP 3 LASTPIN (-25 3000) SIG_NAME M_E_DQ<33>
J 0
(-15 3010);
DISPLAY 0.659574 (-15 3010);
PAINT MONO (-15 3010);
DISPLAY INVISIBLE (-15 3010);
FORCEPROP 1 LASTPIN (-25 3000) BN 33
J 2
(25 3010);
DISPLAY 0.617021 (25 3010);
PAINT PINK (25 3010);
FORCEPROP 2 LAST CDS_LIB mstr_standard
J 2
(25 3000);
DISPLAY 0.787234 (25 3000);
PAINT MONO (25 3000);
DISPLAY INVISIBLE (25 3000);
FORCEPROP 1 LAST BODY_TYPE PLUMBING
J 2
(25 2950);
DISPLAY 1.234043 (25 2950);
PAINT GREEN (25 2950);
DISPLAY INVISIBLE (25 2950);
FORCEPROP 1 LAST HDL_TAP TRUE
J 2
(-300 2875);
DISPLAY 1.234043 (-300 2875);
PAINT GREEN (-300 2875);
DISPLAY INVISIBLE (-300 2875);
FORCEPROP 1 LAST PATH I84
J 2
(27 3000);
DISPLAY 0.872340 (27 3000);
PAINT GREEN (27 3000);
DISPLAY INVISIBLE (27 3000);
FORCEADD TAP..6
R 2
(25 2950);
FORCEPROP 3 LASTPIN (-25 2950) SIG_NAME M_E_DQ<32>
J 0
(-15 2960);
DISPLAY 0.659574 (-15 2960);
PAINT MONO (-15 2960);
DISPLAY INVISIBLE (-15 2960);
FORCEPROP 1 LASTPIN (-25 2950) BN 32
J 2
(25 2960);
DISPLAY 0.617021 (25 2960);
PAINT PINK (25 2960);
FORCEPROP 2 LAST CDS_LIB mstr_standard
J 2
(25 2950);
DISPLAY 0.787234 (25 2950);
PAINT MONO (25 2950);
DISPLAY INVISIBLE (25 2950);
FORCEPROP 1 LAST BODY_TYPE PLUMBING
J 2
(25 2900);
DISPLAY 1.234043 (25 2900);
PAINT GREEN (25 2900);
DISPLAY INVISIBLE (25 2900);
FORCEPROP 1 LAST HDL_TAP TRUE
J 2
(-300 2825);
DISPLAY 1.234043 (-300 2825);
PAINT GREEN (-300 2825);
DISPLAY INVISIBLE (-300 2825);
FORCEPROP 1 LAST PATH I85
J 2
(27 2950);
DISPLAY 0.872340 (27 2950);
PAINT GREEN (27 2950);
DISPLAY INVISIBLE (27 2950);
FORCEADD TAP..6
R 2
(25 3150);
FORCEPROP 3 LASTPIN (-25 3150) SIG_NAME M_E_DQ<36>
J 0
(-15 3160);
DISPLAY 0.659574 (-15 3160);
PAINT MONO (-15 3160);
DISPLAY INVISIBLE (-15 3160);
FORCEPROP 1 LASTPIN (-25 3150) BN 36
J 2
(25 3160);
DISPLAY 0.617021 (25 3160);
PAINT PINK (25 3160);
FORCEPROP 2 LAST CDS_LIB mstr_standard
J 2
(25 3150);
DISPLAY 0.787234 (25 3150);
PAINT MONO (25 3150);
DISPLAY INVISIBLE (25 3150);
FORCEPROP 1 LAST BODY_TYPE PLUMBING
J 2
(25 3100);
DISPLAY 1.234043 (25 3100);
PAINT GREEN (25 3100);
DISPLAY INVISIBLE (25 3100);
FORCEPROP 1 LAST HDL_TAP TRUE
J 2
(-300 3025);
DISPLAY 1.234043 (-300 3025);
PAINT GREEN (-300 3025);
DISPLAY INVISIBLE (-300 3025);
FORCEPROP 1 LAST PATH I86
J 2
(27 3150);
DISPLAY 0.872340 (27 3150);
PAINT GREEN (27 3150);
DISPLAY INVISIBLE (27 3150);
FORCEADD TAP..6
R 2
(25 3100);
FORCEPROP 3 LASTPIN (-25 3100) SIG_NAME M_E_DQ<35>
J 0
(-15 3110);
DISPLAY 0.659574 (-15 3110);
PAINT MONO (-15 3110);
DISPLAY INVISIBLE (-15 3110);
FORCEPROP 1 LASTPIN (-25 3100) BN 35
J 2
(25 3110);
DISPLAY 0.617021 (25 3110);
PAINT PINK (25 3110);
FORCEPROP 2 LAST CDS_LIB mstr_standard
J 2
(25 3100);
DISPLAY 0.787234 (25 3100);
PAINT MONO (25 3100);
DISPLAY INVISIBLE (25 3100);
FORCEPROP 1 LAST BODY_TYPE PLUMBING
J 2
(25 3050);
DISPLAY 1.234043 (25 3050);
PAINT GREEN (25 3050);
DISPLAY INVISIBLE (25 3050);
FORCEPROP 1 LAST HDL_TAP TRUE
J 2
(-300 2975);
DISPLAY 1.234043 (-300 2975);
PAINT GREEN (-300 2975);
DISPLAY INVISIBLE (-300 2975);
FORCEPROP 1 LAST PATH I87
J 2
(27 3100);
DISPLAY 0.872340 (27 3100);
PAINT GREEN (27 3100);
DISPLAY INVISIBLE (27 3100);
FORCEADD TAP..6
R 2
(25 3300);
FORCEPROP 3 LASTPIN (-25 3300) SIG_NAME M_E_DQ<39>
J 0
(-15 3310);
DISPLAY 0.659574 (-15 3310);
PAINT MONO (-15 3310);
DISPLAY INVISIBLE (-15 3310);
FORCEPROP 1 LASTPIN (-25 3300) BN 39
J 2
(25 3310);
DISPLAY 0.617021 (25 3310);
PAINT PINK (25 3310);
FORCEPROP 2 LAST CDS_LIB mstr_standard
J 2
(25 3300);
DISPLAY 0.787234 (25 3300);
PAINT MONO (25 3300);
DISPLAY INVISIBLE (25 3300);
FORCEPROP 1 LAST BODY_TYPE PLUMBING
J 2
(25 3250);
DISPLAY 1.234043 (25 3250);
PAINT GREEN (25 3250);
DISPLAY INVISIBLE (25 3250);
FORCEPROP 1 LAST HDL_TAP TRUE
J 2
(-300 3175);
DISPLAY 1.234043 (-300 3175);
PAINT GREEN (-300 3175);
DISPLAY INVISIBLE (-300 3175);
FORCEPROP 1 LAST PATH I88
J 2
(27 3300);
DISPLAY 0.872340 (27 3300);
PAINT GREEN (27 3300);
DISPLAY INVISIBLE (27 3300);
FORCEADD TAP..6
R 2
(25 3250);
FORCEPROP 3 LASTPIN (-25 3250) SIG_NAME M_E_DQ<38>
J 0
(-15 3260);
DISPLAY 0.659574 (-15 3260);
PAINT MONO (-15 3260);
DISPLAY INVISIBLE (-15 3260);
FORCEPROP 1 LASTPIN (-25 3250) BN 38
J 2
(25 3260);
DISPLAY 0.617021 (25 3260);
PAINT PINK (25 3260);
FORCEPROP 2 LAST CDS_LIB mstr_standard
J 2
(25 3250);
DISPLAY 0.787234 (25 3250);
PAINT MONO (25 3250);
DISPLAY INVISIBLE (25 3250);
FORCEPROP 1 LAST BODY_TYPE PLUMBING
J 2
(25 3200);
DISPLAY 1.234043 (25 3200);
PAINT GREEN (25 3200);
DISPLAY INVISIBLE (25 3200);
FORCEPROP 1 LAST HDL_TAP TRUE
J 2
(-300 3125);
DISPLAY 1.234043 (-300 3125);
PAINT GREEN (-300 3125);
DISPLAY INVISIBLE (-300 3125);
FORCEPROP 1 LAST PATH I89
J 2
(27 3250);
DISPLAY 0.872340 (27 3250);
PAINT GREEN (27 3250);
DISPLAY INVISIBLE (27 3250);
FORCEADD OFFPAGE..1
(-2125 1050);
FORCEPROP 2 LAST $XR0 89 
J 0
(-2346 1050);
DISPLAY 0.638298 (-2346 1050);
PAINT MONO (-2346 1050);
FORCEPROP 2 LAST $XR1 49 
J 0
(-2436 1050);
DISPLAY 0.638298 (-2436 1050);
PAINT MONO (-2436 1050);
FORCEPROP 2 LAST $XR2 50 
J 0
(-2526 1050);
DISPLAY 0.638298 (-2526 1050);
PAINT MONO (-2526 1050);
FORCEPROP 2 LAST $XR3 51 
J 0
(-2616 1050);
DISPLAY 0.638298 (-2616 1050);
PAINT MONO (-2616 1050);
FORCEPROP 2 LAST $XR4 53 
J 0
(-2706 1050);
DISPLAY 0.638298 (-2706 1050);
PAINT MONO (-2706 1050);
FORCEPROP 2 LAST $XR5 54 
J 0
(-2796 1050);
DISPLAY 0.638298 (-2796 1050);
PAINT MONO (-2796 1050);
FORCEPROP 2 LAST CDS_LIB mstr_standard
J 0
(-2125 1050);
PAINT ORANGE (-2125 1050);
DISPLAY INVISIBLE (-2125 1050);
FORCEPROP 1 LAST OFFPAGE TRUE
J 0
(-1800 925);
DISPLAY 0.936170 (-1800 925);
PAINT GREEN (-1800 925);
DISPLAY INVISIBLE (-1800 925);
FORCEPROP 1 LAST COMMENT_BODY TRUE
J 0
(-2000 950);
DISPLAY 0.936170 (-2000 950);
PAINT GREEN (-2000 950);
DISPLAY INVISIBLE (-2000 950);
FORCEPROP 2 LAST PATH I9
J 0
(-2375 1100);
DISPLAY 1.021277 (-2375 1100);
PAINT ORANGE (-2375 1100);
DISPLAY INVISIBLE (-2375 1100);
FORCEADD TAP..6
R 2
(25 3200);
FORCEPROP 3 LASTPIN (-25 3200) SIG_NAME M_E_DQ<37>
J 0
(-15 3210);
DISPLAY 0.659574 (-15 3210);
PAINT MONO (-15 3210);
DISPLAY INVISIBLE (-15 3210);
FORCEPROP 1 LASTPIN (-25 3200) BN 37
J 2
(25 3210);
DISPLAY 0.617021 (25 3210);
PAINT PINK (25 3210);
FORCEPROP 2 LAST CDS_LIB mstr_standard
J 2
(25 3200);
DISPLAY 0.787234 (25 3200);
PAINT MONO (25 3200);
DISPLAY INVISIBLE (25 3200);
FORCEPROP 1 LAST BODY_TYPE PLUMBING
J 2
(25 3150);
DISPLAY 1.234043 (25 3150);
PAINT GREEN (25 3150);
DISPLAY INVISIBLE (25 3150);
FORCEPROP 1 LAST HDL_TAP TRUE
J 2
(-300 3075);
DISPLAY 1.234043 (-300 3075);
PAINT GREEN (-300 3075);
DISPLAY INVISIBLE (-300 3075);
FORCEPROP 1 LAST PATH I90
J 2
(27 3200);
DISPLAY 0.872340 (27 3200);
PAINT GREEN (27 3200);
DISPLAY INVISIBLE (27 3200);
FORCEADD TAP..6
R 2
(25 3350);
FORCEPROP 3 LASTPIN (-25 3350) SIG_NAME M_E_DQ<40>
J 0
(-15 3360);
DISPLAY 0.659574 (-15 3360);
PAINT MONO (-15 3360);
DISPLAY INVISIBLE (-15 3360);
FORCEPROP 1 LASTPIN (-25 3350) BN 40
J 2
(25 3360);
DISPLAY 0.617021 (25 3360);
PAINT PINK (25 3360);
FORCEPROP 2 LAST CDS_LIB mstr_standard
J 2
(25 3350);
DISPLAY 0.787234 (25 3350);
PAINT MONO (25 3350);
DISPLAY INVISIBLE (25 3350);
FORCEPROP 1 LAST BODY_TYPE PLUMBING
J 2
(25 3300);
DISPLAY 1.234043 (25 3300);
PAINT GREEN (25 3300);
DISPLAY INVISIBLE (25 3300);
FORCEPROP 1 LAST HDL_TAP TRUE
J 2
(-300 3225);
DISPLAY 1.234043 (-300 3225);
PAINT GREEN (-300 3225);
DISPLAY INVISIBLE (-300 3225);
FORCEPROP 1 LAST PATH I91
J 2
(27 3350);
DISPLAY 0.872340 (27 3350);
PAINT GREEN (27 3350);
DISPLAY INVISIBLE (27 3350);
FORCEADD TAP..6
R 2
(25 3400);
FORCEPROP 3 LASTPIN (-25 3400) SIG_NAME M_E_DQ<41>
J 0
(-15 3410);
DISPLAY 0.659574 (-15 3410);
PAINT MONO (-15 3410);
DISPLAY INVISIBLE (-15 3410);
FORCEPROP 1 LASTPIN (-25 3400) BN 41
J 2
(25 3410);
DISPLAY 0.617021 (25 3410);
PAINT PINK (25 3410);
FORCEPROP 2 LAST CDS_LIB mstr_standard
J 2
(25 3400);
DISPLAY 0.787234 (25 3400);
PAINT MONO (25 3400);
DISPLAY INVISIBLE (25 3400);
FORCEPROP 1 LAST BODY_TYPE PLUMBING
J 2
(25 3350);
DISPLAY 1.234043 (25 3350);
PAINT GREEN (25 3350);
DISPLAY INVISIBLE (25 3350);
FORCEPROP 1 LAST HDL_TAP TRUE
J 2
(-300 3275);
DISPLAY 1.234043 (-300 3275);
PAINT GREEN (-300 3275);
DISPLAY INVISIBLE (-300 3275);
FORCEPROP 1 LAST PATH I92
J 2
(27 3400);
DISPLAY 0.872340 (27 3400);
PAINT GREEN (27 3400);
DISPLAY INVISIBLE (27 3400);
FORCEADD TAP..6
R 2
(25 3550);
FORCEPROP 3 LASTPIN (-25 3550) SIG_NAME M_E_DQ<44>
J 0
(-15 3560);
DISPLAY 0.659574 (-15 3560);
PAINT MONO (-15 3560);
DISPLAY INVISIBLE (-15 3560);
FORCEPROP 1 LASTPIN (-25 3550) BN 44
J 2
(25 3560);
DISPLAY 0.617021 (25 3560);
PAINT PINK (25 3560);
FORCEPROP 2 LAST CDS_LIB mstr_standard
J 2
(25 3550);
DISPLAY 0.787234 (25 3550);
PAINT MONO (25 3550);
DISPLAY INVISIBLE (25 3550);
FORCEPROP 1 LAST BODY_TYPE PLUMBING
J 2
(25 3500);
DISPLAY 1.234043 (25 3500);
PAINT GREEN (25 3500);
DISPLAY INVISIBLE (25 3500);
FORCEPROP 1 LAST HDL_TAP TRUE
J 2
(-300 3425);
DISPLAY 1.234043 (-300 3425);
PAINT GREEN (-300 3425);
DISPLAY INVISIBLE (-300 3425);
FORCEPROP 1 LAST PATH I93
J 2
(27 3550);
DISPLAY 0.872340 (27 3550);
PAINT GREEN (27 3550);
DISPLAY INVISIBLE (27 3550);
FORCEADD TAP..6
R 2
(25 3500);
FORCEPROP 3 LASTPIN (-25 3500) SIG_NAME M_E_DQ<43>
J 0
(-15 3510);
DISPLAY 0.659574 (-15 3510);
PAINT MONO (-15 3510);
DISPLAY INVISIBLE (-15 3510);
FORCEPROP 1 LASTPIN (-25 3500) BN 43
J 2
(25 3510);
DISPLAY 0.617021 (25 3510);
PAINT PINK (25 3510);
FORCEPROP 2 LAST CDS_LIB mstr_standard
J 2
(25 3500);
DISPLAY 0.787234 (25 3500);
PAINT MONO (25 3500);
DISPLAY INVISIBLE (25 3500);
FORCEPROP 1 LAST BODY_TYPE PLUMBING
J 2
(25 3450);
DISPLAY 1.234043 (25 3450);
PAINT GREEN (25 3450);
DISPLAY INVISIBLE (25 3450);
FORCEPROP 1 LAST HDL_TAP TRUE
J 2
(-300 3375);
DISPLAY 1.234043 (-300 3375);
PAINT GREEN (-300 3375);
DISPLAY INVISIBLE (-300 3375);
FORCEPROP 1 LAST PATH I94
J 2
(27 3500);
DISPLAY 0.872340 (27 3500);
PAINT GREEN (27 3500);
DISPLAY INVISIBLE (27 3500);
FORCEADD TAP..6
R 2
(25 3450);
FORCEPROP 3 LASTPIN (-25 3450) SIG_NAME M_E_DQ<42>
J 0
(-15 3460);
DISPLAY 0.659574 (-15 3460);
PAINT MONO (-15 3460);
DISPLAY INVISIBLE (-15 3460);
FORCEPROP 1 LASTPIN (-25 3450) BN 42
J 2
(25 3460);
DISPLAY 0.617021 (25 3460);
PAINT PINK (25 3460);
FORCEPROP 2 LAST CDS_LIB mstr_standard
J 2
(25 3450);
DISPLAY 0.787234 (25 3450);
PAINT MONO (25 3450);
DISPLAY INVISIBLE (25 3450);
FORCEPROP 1 LAST BODY_TYPE PLUMBING
J 2
(25 3400);
DISPLAY 1.234043 (25 3400);
PAINT GREEN (25 3400);
DISPLAY INVISIBLE (25 3400);
FORCEPROP 1 LAST HDL_TAP TRUE
J 2
(-300 3325);
DISPLAY 1.234043 (-300 3325);
PAINT GREEN (-300 3325);
DISPLAY INVISIBLE (-300 3325);
FORCEPROP 1 LAST PATH I95
J 2
(27 3450);
DISPLAY 0.872340 (27 3450);
PAINT GREEN (27 3450);
DISPLAY INVISIBLE (27 3450);
FORCEADD TAP..6
R 2
(25 3650);
FORCEPROP 3 LASTPIN (-25 3650) SIG_NAME M_E_DQ<46>
J 0
(-15 3660);
DISPLAY 0.659574 (-15 3660);
PAINT MONO (-15 3660);
DISPLAY INVISIBLE (-15 3660);
FORCEPROP 1 LASTPIN (-25 3650) BN 46
J 2
(25 3660);
DISPLAY 0.617021 (25 3660);
PAINT PINK (25 3660);
FORCEPROP 2 LAST CDS_LIB mstr_standard
J 2
(25 3650);
DISPLAY 0.787234 (25 3650);
PAINT MONO (25 3650);
DISPLAY INVISIBLE (25 3650);
FORCEPROP 1 LAST BODY_TYPE PLUMBING
J 2
(25 3600);
DISPLAY 1.234043 (25 3600);
PAINT GREEN (25 3600);
DISPLAY INVISIBLE (25 3600);
FORCEPROP 1 LAST HDL_TAP TRUE
J 2
(-300 3525);
DISPLAY 1.234043 (-300 3525);
PAINT GREEN (-300 3525);
DISPLAY INVISIBLE (-300 3525);
FORCEPROP 1 LAST PATH I96
J 2
(27 3650);
DISPLAY 0.872340 (27 3650);
PAINT GREEN (27 3650);
DISPLAY INVISIBLE (27 3650);
FORCEADD TAP..6
R 2
(25 3600);
FORCEPROP 3 LASTPIN (-25 3600) SIG_NAME M_E_DQ<45>
J 0
(-15 3610);
DISPLAY 0.659574 (-15 3610);
PAINT MONO (-15 3610);
DISPLAY INVISIBLE (-15 3610);
FORCEPROP 1 LASTPIN (-25 3600) BN 45
J 2
(25 3610);
DISPLAY 0.617021 (25 3610);
PAINT PINK (25 3610);
FORCEPROP 2 LAST CDS_LIB mstr_standard
J 2
(25 3600);
DISPLAY 0.787234 (25 3600);
PAINT MONO (25 3600);
DISPLAY INVISIBLE (25 3600);
FORCEPROP 1 LAST BODY_TYPE PLUMBING
J 2
(25 3550);
DISPLAY 1.234043 (25 3550);
PAINT GREEN (25 3550);
DISPLAY INVISIBLE (25 3550);
FORCEPROP 1 LAST HDL_TAP TRUE
J 2
(-300 3475);
DISPLAY 1.234043 (-300 3475);
PAINT GREEN (-300 3475);
DISPLAY INVISIBLE (-300 3475);
FORCEPROP 1 LAST PATH I97
J 2
(27 3600);
DISPLAY 0.872340 (27 3600);
PAINT GREEN (27 3600);
DISPLAY INVISIBLE (27 3600);
FORCEADD PVTT_DEF..1
(625 2350);
FORCEPROP 3 LASTPIN (625 2300) SIG_NAME PVTT_DEF\g
J 0
(635 2310);
DISPLAY 0.659574 (635 2310);
PAINT MONO (635 2310);
DISPLAY INVISIBLE (635 2310);
FORCEPROP 1 LAST VOLTAGE 0.6V
J 0
(580 2307);
DISPLAY 0.340426 (580 2307);
PAINT SKYBLUE (580 2307);
DISPLAY INVISIBLE (580 2307);
FORCEPROP 2 LAST CDS_LIB mstr_symbols
J 0
(625 2350);
PAINT ORANGE (625 2350);
DISPLAY INVISIBLE (625 2350);
FORCEPROP 1 LAST BODY_TYPE PLUMBING
J 0
(580 2307);
DISPLAY 0.340426 (580 2307);
PAINT GREEN (580 2307);
DISPLAY INVISIBLE (580 2307);
FORCEPROP 1 LAST PATH I98
J 0
(675 2375);
DISPLAY 0.872340 (675 2375);
PAINT AQUA (675 2375);
DISPLAY INVISIBLE (675 2375);
FORCEPROP 1 LAST HDL_POWER PVTT_DEF
J 1
(625 2400);
DISPLAY 0.872340 (625 2400);
PAINT GREEN (625 2400);
DISPLAY INVISIBLE (625 2400);
FORCEADD PVPP_DEF..1
(775 2650);
FORCEPROP 3 LASTPIN (775 2600) SIG_NAME PVPP_DEF\g
J 0
(785 2610);
DISPLAY 0.659574 (785 2610);
PAINT MONO (785 2610);
DISPLAY INVISIBLE (785 2610);
FORCEPROP 1 LAST VOLTAGE 2.5V
J 0
(730 2607);
DISPLAY 0.340426 (730 2607);
PAINT SKYBLUE (730 2607);
DISPLAY INVISIBLE (730 2607);
FORCEPROP 2 LAST CDS_LIB mstr_symbols
J 0
(775 2650);
PAINT ORANGE (775 2650);
DISPLAY INVISIBLE (775 2650);
FORCEPROP 1 LAST BODY_TYPE PLUMBING
J 0
(730 2607);
DISPLAY 0.340426 (730 2607);
PAINT GREEN (730 2607);
DISPLAY INVISIBLE (730 2607);
FORCEPROP 1 LAST PATH I99
J 0
(825 2675);
DISPLAY 0.872340 (825 2675);
PAINT AQUA (825 2675);
DISPLAY INVISIBLE (825 2675);
FORCEPROP 1 LAST HDL_POWER PVPP_DEF
J 1
(775 2700);
DISPLAY 0.872340 (775 2700);
PAINT GREEN (775 2700);
DISPLAY INVISIBLE (775 2700);
FORCEADD BOM_NOTE..1
(-3400 5000);
FORCEPROP 0 LAST L1 UNSTUFF FOR SKU B
J 0
(-3550 4900);
DISPLAY 1.063830 (-3550 4900);
PAINT WHITE (-3550 4900);
FORCEPROP 2 LAST CDS_LIB mstr_symbols
J 0
(-3400 5000);
PAINT ORANGE (-3400 5000);
DISPLAY INVISIBLE (-3400 5000);
FORCEPROP 1 LAST COMMENT_BODY TRUE
J 0
(-3375 5100);
DISPLAY 1.319149 (-3375 5100);
PAINT ORANGE (-3375 5100);
DISPLAY INVISIBLE (-3375 5100);
FORCEADD INTEL_CORP_BPAGE..1
(4250 200);
FORCEPROP 1 LAST CDS_CON_LAST_MODIFIED Tue Dec 01 11:51:31 2015
J 0
(2825 525);
PAINT ORANGE (2825 525);
DISPLAY INVISIBLE (2825 525);
FORCEPROP 1 LAST CUSTOM_TXT_CDS <CURRENT_DESIGN_SHEET> OF <TOTAL_DESIGN_SHEETS>
J 0
(3750 225);
PAINT GREEN (3750 225);
FORCEPROP 1 LAST CUSTOM_TXT_CDS <CON_LAST_MODIFIED>
J 0
(2325 550);
PAINT GREEN (2325 550);
FORCEPROP 2 LAST CUSTOM_TXT_CDS <XR_PAGE_TITLE>
J 0
(-3640 5450);
DISPLAY 0.638298 (-3640 5450);
PAINT PINK (-3640 5450);
DISPLAY INVISIBLE (-3640 5450);
FORCEPROP 1 LAST SCH_ADDRESS3 Santa Clara, CA 95052-8119
J 0
(275 225);
DISPLAY 0.617021 (275 225);
PAINT GREEN (275 225);
FORCEPROP 1 LAST SCH_ADDRESS2 P.O. BOX 58119
J 0
(275 275);
DISPLAY 0.617021 (275 275);
PAINT GREEN (275 275);
FORCEPROP 1 LAST SCH_ADDRESS1 2200 Mission College Blvd.
J 0
(275 325);
DISPLAY 0.617021 (275 325);
PAINT GREEN (275 325);
FORCEPROP 1 LAST SCH_TITLE CPU0 DDR4 CH E DIMM1
J 0
(-3700 250);
DISPLAY 1.212766 (-3700 250);
PAINT ORANGE (-3700 250);
FORCEPROP 1 LAST SCH_REV 2.420
J 0
(4000 350);
DISPLAY 0.978723 (4000 350);
PAINT YELLOW (4000 350);
FORCEPROP 1 LAST SCH_DEPT BESD
J 1
(-200 300);
DISPLAY 1.212766 (-200 300);
PAINT YELLOW (-200 300);
FORCEPROP 1 LAST SCH_NUMBER H4694802
J 0
(2950 350);
DISPLAY 1.212766 (2950 350);
PAINT YELLOW (2950 350);
FORCEPROP 2 LAST PAGE_BORDER TRUE
J 0
(-3640 5450);
DISPLAY 0.638298 (-3640 5450);
PAINT PINK (-3640 5450);
DISPLAY INVISIBLE (-3640 5450);
FORCEPROP 2 LAST CDS_LIB mstr_symbols
J 0
(4250 200);
PAINT MONO (4250 200);
DISPLAY INVISIBLE (4250 200);
FORCEPROP 1 LAST COMMENT_BODY TRUE
J 0
(4262 212);
DISPLAY 0.468085 (4262 212);
PAINT GREEN (4262 212);
DISPLAY INVISIBLE (4262 212);
FORCEPROP 2 LAST CDS_XR_PAGE_TITLE CR-52 : @BASEBOARD_FAB2_LIB.BASEBOARD_FAB2(SCH_1):PAGE52
J 0
(-3640 5450);
DISPLAY 0.638298 (-3640 5450);
PAINT PINK (-3640 5450);
DISPLAY INVISIBLE (-3640 5450);
WIRE 17 -1 (2575 4725)(2575 4750);
WIRE 17 -1 (2575 4625)(2575 4725);
WIRE 17 -1 (3175 4750)(2575 4750);
FORCEPROP 2 LAST SIG_NAME M_E_DQS_DN<17:0>
J 0
(2625 4760);
DISPLAY 0.617021 (2625 4760);
PAINT ORANGE (2625 4760);
WIRE 17 -1 (2375 4775)(2375 4800);
WIRE 17 -1 (2375 4675)(2375 4775);
WIRE 17 -1 (3175 4800)(2375 4800);
FORCEPROP 2 LAST SIG_NAME M_E_DQS_DP<17:0>
J 0
(2625 4810);
DISPLAY 0.617021 (2625 4810);
PAINT ORANGE (2625 4810);
WIRE 17 -1 (2375 4575)(2375 4675);
WIRE 17 -1 (2575 4525)(2575 4625);
WIRE 17 -1 (2575 4425)(2575 4525);
WIRE 17 -1 (2575 4325)(2575 4425);
WIRE 17 -1 (2575 4225)(2575 4325);
WIRE 17 -1 (2575 4125)(2575 4225);
WIRE 17 -1 (2575 4025)(2575 4125);
WIRE 17 -1 (2575 3925)(2575 4025);
WIRE 17 -1 (2575 3825)(2575 3925);
WIRE 17 -1 (2575 3725)(2575 3825);
WIRE 17 -1 (2575 3625)(2575 3725);
WIRE 17 -1 (2575 3525)(2575 3625);
WIRE 17 -1 (2575 3425)(2575 3525);
WIRE 17 -1 (2375 4475)(2375 4575);
WIRE 17 -1 (2375 4375)(2375 4475);
WIRE 17 -1 (2375 4275)(2375 4375);
WIRE 17 -1 (2375 4175)(2375 4275);
WIRE 17 -1 (2375 4075)(2375 4175);
WIRE 17 -1 (2375 3975)(2375 4075);
WIRE 17 -1 (2375 3875)(2375 3975);
WIRE 17 -1 (2375 3775)(2375 3875);
WIRE 17 -1 (2375 3675)(2375 3775);
WIRE 17 -1 (2375 3575)(2375 3675);
WIRE 17 -1 (2375 3475)(2375 3575);
WIRE 17 -1 (2575 3325)(2575 3425);
WIRE 17 -1 (2575 3225)(2575 3325);
WIRE 17 -1 (2575 3125)(2575 3225);
WIRE 17 -1 (2575 3025)(2575 3125);
WIRE 17 -1 (2375 3375)(2375 3475);
WIRE 17 -1 (2375 3275)(2375 3375);
WIRE 17 -1 (2375 3175)(2375 3275);
WIRE 17 -1 (2375 3075)(2375 3175);
WIRE 17 -1 (75 4425)(75 4475);
WIRE 17 -1 (75 4375)(75 4425);
WIRE 17 -1 (75 4475)(75 4525);
WIRE 17 -1 (75 4525)(75 4550);
WIRE 17 -1 (75 4325)(75 4375);
WIRE 17 -1 (75 4275)(75 4325);
WIRE 17 -1 (525 4550)(75 4550);
FORCEPROP 2 LAST SIG_NAME M_E_DQ<63:0>
J 0
(115 4560);
DISPLAY 0.617021 (115 4560);
PAINT ORANGE (115 4560);
WIRE 17 -1 (75 4225)(75 4275);
WIRE 17 -1 (75 4175)(75 4225);
WIRE 17 -1 (75 4125)(75 4175);
WIRE 17 -1 (75 4075)(75 4125);
WIRE 17 -1 (75 4025)(75 4075);
WIRE 17 -1 (75 3975)(75 4025);
WIRE 17 -1 (75 3925)(75 3975);
WIRE 17 -1 (75 3875)(75 3925);
WIRE 17 -1 (75 3825)(75 3875);
WIRE 17 -1 (75 3775)(75 3825);
WIRE 17 -1 (75 3725)(75 3775);
WIRE 17 -1 (75 3675)(75 3725);
WIRE 17 -1 (-1525 4475)(-1525 4525);
WIRE 17 -1 (-1525 4425)(-1525 4475);
WIRE 17 -1 (-1525 4525)(-1525 4550);
WIRE 17 -1 (-2225 4550)(-1525 4550);
FORCEPROP 2 LAST SIG_NAME M_E_MA<17:0>
J 0
(-2175 4560);
DISPLAY 0.617021 (-2175 4560);
PAINT ORANGE (-2175 4560);
WIRE 17 -1 (-1525 4375)(-1525 4425);
WIRE 17 -1 (-1525 4325)(-1525 4375);
WIRE 17 -1 (-1525 4275)(-1525 4325);
WIRE 17 -1 (-1525 4225)(-1525 4275);
WIRE 17 -1 (-1525 4175)(-1525 4225);
WIRE 17 -1 (-1525 4125)(-1525 4175);
WIRE 17 -1 (-1525 4075)(-1525 4125);
WIRE 17 -1 (-1525 4025)(-1525 4075);
WIRE 17 -1 (-1525 3975)(-1525 4025);
WIRE 17 -1 (-1525 3925)(-1525 3975);
WIRE 17 -1 (-1525 3875)(-1525 3925);
WIRE 17 -1 (-1525 3825)(-1525 3875);
WIRE 17 -1 (-1525 3775)(-1525 3825);
WIRE 17 -1 (-1525 3725)(-1525 3775);
WIRE 17 -1 (-1525 3675)(-1525 3725);
WIRE 17 -1 (75 3625)(75 3675);
WIRE 17 -1 (75 3575)(75 3625);
WIRE 17 -1 (75 3525)(75 3575);
WIRE 17 -1 (75 3475)(75 3525);
WIRE 17 -1 (75 3425)(75 3475);
WIRE 17 -1 (75 3375)(75 3425);
WIRE 17 -1 (75 3325)(75 3375);
WIRE 17 -1 (75 3275)(75 3325);
WIRE 17 -1 (75 3225)(75 3275);
WIRE 17 -1 (75 3175)(75 3225);
WIRE 17 -1 (75 3125)(75 3175);
WIRE 17 -1 (75 3075)(75 3125);
WIRE 17 -1 (75 3025)(75 3075);
WIRE 17 -1 (75 2975)(75 3025);
WIRE 17 -1 (75 2925)(75 2975);
WIRE 17 -1 (75 2875)(75 2925);
WIRE 17 -1 (75 2825)(75 2875);
WIRE 17 -1 (75 2775)(75 2825);
WIRE 17 -1 (75 2725)(75 2775);
WIRE 17 -1 (75 2675)(75 2725);
WIRE 17 -1 (75 2625)(75 2675);
WIRE 17 -1 (75 2575)(75 2625);
WIRE 17 -1 (75 2525)(75 2575);
WIRE 17 -1 (75 2475)(75 2525);
WIRE 17 -1 (75 2425)(75 2475);
WIRE 17 -1 (75 2375)(75 2425);
WIRE 17 -1 (75 2325)(75 2375);
WIRE 17 -1 (75 2275)(75 2325);
WIRE 17 -1 (75 2225)(75 2275);
WIRE 17 -1 (75 2175)(75 2225);
WIRE 17 -1 (75 2125)(75 2175);
WIRE 17 -1 (75 2075)(75 2125);
WIRE 17 -1 (75 2025)(75 2075);
WIRE 17 -1 (75 1975)(75 2025);
WIRE 17 -1 (75 1925)(75 1975);
WIRE 17 -1 (75 1875)(75 1925);
WIRE 17 -1 (75 1825)(75 1875);
WIRE 17 -1 (75 1775)(75 1825);
WIRE 17 -1 (75 1725)(75 1775);
WIRE 17 -1 (75 1675)(75 1725);
WIRE 17 -1 (75 1625)(75 1675);
WIRE 17 -1 (75 1575)(75 1625);
WIRE 17 -1 (75 1525)(75 1575);
WIRE 17 -1 (75 1475)(75 1525);
WIRE 17 -1 (75 1425)(75 1475);
WIRE 17 -1 (75 1375)(75 1425);
WIRE 17 -1 (-1525 3525)(-1525 3575);
WIRE 17 -1 (-1525 3650)(-1525 3575);
WIRE 17 -1 (-1525 3650)(-2225 3650);
FORCEPROP 2 LAST SIG_NAME M_E_BA<1:0>
J 0
(-2175 3660);
DISPLAY 0.617021 (-2175 3660);
PAINT ORANGE (-2175 3660);
WIRE 17 -1 (-1525 3475)(-1525 3500);
WIRE 17 -1 (-1525 3425)(-1525 3475);
WIRE 17 -1 (-1525 3500)(-2225 3500);
FORCEPROP 2 LAST SIG_NAME M_E_BG<1:0>
J 0
(-2175 3510);
DISPLAY 0.617021 (-2175 3510);
PAINT ORANGE (-2175 3510);
WIRE 17 -1 (-2075 3175)(-2075 3275);
WIRE 17 -1 (-2075 3275)(-2075 3350);
WIRE 17 -1 (-2075 3350)(-2525 3350);
FORCEPROP 2 LAST SIG_NAME M_E_CLK_DN<3:0>
J 0
(-2500 3360);
DISPLAY 0.617021 (-2500 3360);
PAINT ORANGE (-2500 3360);
WIRE 17 -1 (-1925 3400)(-1925 3325);
WIRE 17 -1 (-1925 3400)(-2525 3400);
FORCEPROP 2 LAST SIG_NAME M_E_CLK_DP<3:0>
J 0
(-2500 3410);
DISPLAY 0.617021 (-2500 3410);
PAINT ORANGE (-2500 3410);
WIRE 17 -1 (-1925 3325)(-1925 3225);
WIRE 17 -1 (-1525 2875)(-1525 2925);
WIRE 17 -1 (-1525 2925)(-1525 2975);
WIRE 17 -1 (-1525 2975)(-1525 3025);
WIRE 17 -1 (-1525 3025)(-1525 3050);
WIRE 17 -1 (-1525 3050)(-2225 3050);
FORCEPROP 2 LAST SIG_NAME M_E_CS_N<7:0>
J 0
(-2200 3060);
DISPLAY 0.617021 (-2200 3060);
PAINT ORANGE (-2200 3060);
WIRE 17 -1 (-1575 2725)(-1575 2775);
WIRE 17 -1 (-1575 2775)(-1575 2800);
WIRE 17 -1 (-1575 2800)(-2225 2800);
FORCEPROP 2 LAST SIG_NAME M_E_CKE<3:0>
J 0
(-2200 2810);
DISPLAY 0.617021 (-2200 2810);
PAINT ORANGE (-2200 2810);
WIRE 17 -1 (-1525 2625)(-1525 2650);
WIRE 17 -1 (-1525 2575)(-1525 2625);
WIRE 17 -1 (-1525 2650)(-2225 2650);
FORCEPROP 2 LAST SIG_NAME M_E_ODT<3:0>
J 0
(-2200 2660);
DISPLAY 0.617021 (-2200 2660);
PAINT ORANGE (-2200 2660);
WIRE 17 -1 (-1525 2475)(-1525 2500);
WIRE 17 -1 (-1525 2425)(-1525 2475);
WIRE 17 -1 (-1525 2500)(-2225 2500);
FORCEPROP 2 LAST SIG_NAME M_E_ECC<7:0>
J 0
(-2200 2510);
DISPLAY 0.617021 (-2200 2510);
PAINT ORANGE (-2200 2510);
WIRE 17 -1 (-1525 2125)(-1525 2175);
WIRE 17 -1 (-1525 2175)(-1525 2225);
WIRE 17 -1 (-1525 2225)(-1525 2275);
WIRE 17 -1 (-1525 2275)(-1525 2325);
WIRE 17 -1 (-1525 2325)(-1525 2375);
WIRE 17 -1 (-1525 2375)(-1525 2425);
WIRE 16 -1 (-3575 1650)(-1225 1650);
WIRE 16 -1 (-3575 1650)(-3575 1550);
WIRE 16 -1 (2725 3250)(2925 3250);
WIRE 16 -1 (2725 3200)(2725 3250);
WIRE 16 -1 (2725 3200)(2925 3200);
WIRE 16 -1 (2725 3150)(2725 3200);
WIRE 16 -1 (2725 3150)(2925 3150);
WIRE 16 -1 (2725 3100)(2725 3150);
WIRE 16 -1 (2725 3100)(2925 3100);
WIRE 16 -1 (2725 3050)(2725 3100);
WIRE 16 -1 (2725 3050)(2925 3050);
WIRE 16 -1 (2725 3000)(2725 3050);
WIRE 16 -1 (2725 3000)(2925 3000);
WIRE 16 -1 (2725 2950)(2725 3000);
WIRE 16 -1 (2725 2950)(2925 2950);
WIRE 16 -1 (2725 2900)(2725 2950);
WIRE 16 -1 (2725 2900)(2925 2900);
WIRE 16 -1 (2725 2850)(2725 2900);
WIRE 16 -1 (2725 2850)(2925 2850);
WIRE 16 -1 (2725 2800)(2725 2850);
WIRE 16 -1 (2725 2800)(2925 2800);
WIRE 16 -1 (2725 2750)(2725 2800);
WIRE 16 -1 (2725 2750)(2925 2750);
WIRE 16 -1 (2725 2700)(2725 2750);
WIRE 16 -1 (2725 2700)(2925 2700);
WIRE 16 -1 (2725 2650)(2725 2700);
WIRE 16 -1 (2725 2650)(2925 2650);
WIRE 16 -1 (2725 2600)(2725 2650);
WIRE 16 -1 (2725 2600)(2925 2600);
WIRE 16 -1 (2725 2550)(2725 2600);
WIRE 16 -1 (2725 2550)(2925 2550);
WIRE 16 -1 (2725 2500)(2725 2550);
WIRE 16 -1 (2725 2500)(2925 2500);
WIRE 16 -1 (2725 2450)(2725 2500);
WIRE 16 -1 (2725 2450)(2925 2450);
WIRE 16 -1 (2725 2400)(2725 2450);
WIRE 16 -1 (2725 2400)(2925 2400);
WIRE 16 -1 (2725 2350)(2725 2400);
WIRE 16 -1 (2725 2350)(2925 2350);
WIRE 16 -1 (2725 2300)(2725 2350);
WIRE 16 -1 (2725 2300)(2925 2300);
WIRE 16 -1 (2725 2250)(2725 2300);
WIRE 16 -1 (2725 2250)(2925 2250);
WIRE 16 -1 (2725 2200)(2725 2250);
WIRE 16 -1 (2725 2200)(2925 2200);
WIRE 16 -1 (2725 2150)(2725 2200);
WIRE 16 -1 (2725 2150)(2925 2150);
WIRE 16 -1 (2725 2100)(2725 2150);
WIRE 16 -1 (2725 2100)(2925 2100);
WIRE 16 -1 (2725 2050)(2725 2100);
WIRE 16 -1 (2725 2050)(2925 2050);
WIRE 16 -1 (2725 2000)(2725 2050);
WIRE 16 -1 (2725 2000)(2925 2000);
WIRE 16 -1 (2725 1950)(2725 2000);
WIRE 16 -1 (2725 1950)(2925 1950);
WIRE 16 -1 (2725 1900)(2725 1950);
WIRE 16 -1 (2725 1900)(2925 1900);
WIRE 16 -1 (2725 1850)(2725 1900);
WIRE 16 -1 (2725 1850)(2925 1850);
WIRE 16 -1 (2725 1800)(2725 1850);
WIRE 16 -1 (2725 1800)(2925 1800);
WIRE 16 -1 (2725 1750)(2725 1800);
WIRE 16 -1 (2725 1750)(2925 1750);
WIRE 16 -1 (2725 1700)(2725 1750);
WIRE 16 -1 (2725 1700)(2925 1700);
WIRE 16 -1 (2725 1650)(2725 1700);
WIRE 16 -1 (2725 1650)(2925 1650);
WIRE 16 -1 (2725 1600)(2725 1650);
WIRE 16 -1 (2725 1600)(2925 1600);
WIRE 16 -1 (2725 1550)(2725 1600);
WIRE 16 -1 (2725 1550)(2925 1550);
WIRE 16 -1 (2725 1500)(2725 1550);
WIRE 16 -1 (2725 1500)(2925 1500);
WIRE 16 -1 (2725 1450)(2725 1500);
WIRE 16 -1 (2725 1450)(2925 1450);
WIRE 16 -1 (2725 1400)(2725 1450);
WIRE 16 -1 (2725 1400)(2925 1400);
WIRE 16 -1 (2725 1350)(2725 1400);
WIRE 16 -1 (2725 1350)(2925 1350);
WIRE 16 -1 (2725 1300)(2725 1350);
WIRE 16 -1 (2725 1300)(2925 1300);
WIRE 16 -1 (2725 1250)(2725 1300);
WIRE 16 -1 (2725 1250)(2925 1250);
WIRE 16 -1 (2725 1200)(2725 1250);
WIRE 16 -1 (2725 1200)(2925 1200);
WIRE 16 -1 (2725 1150)(2725 1200);
WIRE 16 -1 (2725 1150)(2925 1150);
WIRE 16 -1 (2725 1100)(2725 1150);
WIRE 16 -1 (2725 1100)(2925 1100);
WIRE 16 -1 (2725 1050)(2725 1100);
WIRE 16 -1 (2725 1050)(2925 1050);
WIRE 16 -1 (2725 1000)(2725 1050);
WIRE 16 -1 (2725 1000)(2925 1000);
WIRE 16 -1 (2725 950)(2725 1000);
WIRE 16 -1 (2725 950)(2925 950);
WIRE 16 -1 (2725 850)(2725 950);
WIRE 16 -1 (4125 3200)(4125 3250);
WIRE 16 -1 (4125 3150)(4125 3200);
WIRE 16 -1 (4125 3200)(3925 3200);
WIRE 16 -1 (4125 3250)(3925 3250);
WIRE 16 -1 (4125 3100)(4125 3150);
WIRE 16 -1 (4125 3150)(3925 3150);
WIRE 16 -1 (4125 3050)(4125 3100);
WIRE 16 -1 (4125 3100)(3925 3100);
WIRE 16 -1 (4125 3000)(4125 3050);
WIRE 16 -1 (4125 3050)(3925 3050);
WIRE 16 -1 (4125 2950)(4125 3000);
WIRE 16 -1 (4125 3000)(3925 3000);
WIRE 16 -1 (4125 2900)(4125 2950);
WIRE 16 -1 (4125 2950)(3925 2950);
WIRE 16 -1 (4125 2850)(4125 2900);
WIRE 16 -1 (4125 2900)(3925 2900);
WIRE 16 -1 (4125 2800)(4125 2850);
WIRE 16 -1 (4125 2850)(3925 2850);
WIRE 16 -1 (4125 2750)(4125 2800);
WIRE 16 -1 (4125 2800)(3925 2800);
WIRE 16 -1 (4125 2700)(4125 2750);
WIRE 16 -1 (4125 2750)(3925 2750);
WIRE 16 -1 (4125 2650)(4125 2700);
WIRE 16 -1 (4125 2700)(3925 2700);
WIRE 16 -1 (4125 2600)(4125 2650);
WIRE 16 -1 (4125 2650)(3925 2650);
WIRE 16 -1 (4125 2550)(4125 2600);
WIRE 16 -1 (4125 2600)(3925 2600);
WIRE 16 -1 (4125 2500)(4125 2550);
WIRE 16 -1 (4125 2550)(3925 2550);
WIRE 16 -1 (4125 2450)(4125 2500);
WIRE 16 -1 (4125 2500)(3925 2500);
WIRE 16 -1 (4125 2400)(4125 2450);
WIRE 16 -1 (4125 2450)(3925 2450);
WIRE 16 -1 (4125 2350)(4125 2400);
WIRE 16 -1 (4125 2400)(3925 2400);
WIRE 16 -1 (4125 2300)(4125 2350);
WIRE 16 -1 (4125 2350)(3925 2350);
WIRE 16 -1 (4125 2250)(4125 2300);
WIRE 16 -1 (4125 2300)(3925 2300);
WIRE 16 -1 (4125 2200)(4125 2250);
WIRE 16 -1 (4125 2250)(3925 2250);
WIRE 16 -1 (4125 2150)(4125 2200);
WIRE 16 -1 (4125 2200)(3925 2200);
WIRE 16 -1 (4125 2100)(4125 2150);
WIRE 16 -1 (4125 2150)(3925 2150);
WIRE 16 -1 (4125 2050)(4125 2100);
WIRE 16 -1 (4125 2100)(3925 2100);
WIRE 16 -1 (4125 2000)(4125 2050);
WIRE 16 -1 (4125 2050)(3925 2050);
WIRE 16 -1 (4125 1950)(4125 2000);
WIRE 16 -1 (4125 2000)(3925 2000);
WIRE 16 -1 (4125 1900)(4125 1950);
WIRE 16 -1 (4125 1950)(3925 1950);
WIRE 16 -1 (4125 1850)(4125 1900);
WIRE 16 -1 (4125 1900)(3925 1900);
WIRE 16 -1 (4125 1800)(4125 1850);
WIRE 16 -1 (4125 1850)(3925 1850);
WIRE 16 -1 (4125 1750)(4125 1800);
WIRE 16 -1 (4125 1800)(3925 1800);
WIRE 16 -1 (4125 1700)(4125 1750);
WIRE 16 -1 (4125 1750)(3925 1750);
WIRE 16 -1 (4125 1650)(4125 1700);
WIRE 16 -1 (4125 1700)(3925 1700);
WIRE 16 -1 (4125 1600)(4125 1650);
WIRE 16 -1 (4125 1650)(3925 1650);
WIRE 16 -1 (4125 1550)(4125 1600);
WIRE 16 -1 (4125 1600)(3925 1600);
WIRE 16 -1 (4125 1500)(4125 1550);
WIRE 16 -1 (4125 1550)(3925 1550);
WIRE 16 -1 (4125 1450)(4125 1500);
WIRE 16 -1 (4125 1500)(3925 1500);
WIRE 16 -1 (4125 1400)(4125 1450);
WIRE 16 -1 (4125 1450)(3925 1450);
WIRE 16 -1 (4125 1350)(4125 1400);
WIRE 16 -1 (4125 1400)(3925 1400);
WIRE 16 -1 (4125 1300)(4125 1350);
WIRE 16 -1 (4125 1350)(3925 1350);
WIRE 16 -1 (4125 1250)(4125 1300);
WIRE 16 -1 (4125 1300)(3925 1300);
WIRE 16 -1 (4125 1200)(4125 1250);
WIRE 16 -1 (4125 1250)(3925 1250);
WIRE 16 -1 (4125 1150)(4125 1200);
WIRE 16 -1 (4125 1200)(3925 1200);
WIRE 16 -1 (4125 1100)(4125 1150);
WIRE 16 -1 (4125 1150)(3925 1150);
WIRE 16 -1 (4125 1050)(4125 1100);
WIRE 16 -1 (4125 1100)(3925 1100);
WIRE 16 -1 (4125 1000)(4125 1050);
WIRE 16 -1 (4125 1050)(3925 1050);
WIRE 16 -1 (4125 950)(4125 1000);
WIRE 16 -1 (4125 1000)(3925 1000);
WIRE 16 -1 (4125 850)(4125 950);
WIRE 16 -1 (4125 950)(3925 950);
WIRE 16 -1 (2175 2450)(2175 2500);
WIRE 16 -1 (2175 2450)(1975 2450);
WIRE 16 -1 (2175 2500)(2175 2675);
WIRE 16 -1 (2175 2500)(1975 2500);
WIRE 16 -1 (-3025 950)(-3025 1050);
WIRE 16 -1 (-1475 1550)(-1225 1550);
WIRE 16 -1 (-1475 1600)(-1475 1550);
WIRE 16 -1 (-1225 1600)(-1475 1600);
WIRE 16 -1 (-1475 1700)(-1475 1600);
WIRE 16 -1 (-1475 1700)(-1225 1700);
WIRE 16 -1 (-3575 1700)(-1475 1700);
WIRE 16 -1 (-3575 1700)(-3575 1800);
WIRE 16 -1 (775 800)(975 800);
WIRE 16 -1 (775 850)(775 800);
WIRE 16 -1 (775 850)(975 850);
WIRE 16 -1 (775 850)(775 900);
WIRE 16 -1 (775 900)(975 900);
WIRE 16 -1 (775 900)(775 950);
WIRE 16 -1 (775 950)(975 950);
WIRE 16 -1 (775 950)(775 1000);
WIRE 16 -1 (775 1000)(775 1050);
WIRE 16 -1 (775 1000)(975 1000);
WIRE 16 -1 (775 1050)(975 1050);
WIRE 16 -1 (775 1050)(775 1100);
WIRE 16 -1 (775 1100)(975 1100);
WIRE 16 -1 (775 1100)(775 1150);
WIRE 16 -1 (775 1150)(975 1150);
WIRE 16 -1 (775 1150)(775 1200);
WIRE 16 -1 (775 1200)(975 1200);
WIRE 16 -1 (775 1200)(775 1250);
WIRE 16 -1 (775 1250)(775 1300);
WIRE 16 -1 (775 1250)(975 1250);
WIRE 16 -1 (775 1300)(975 1300);
WIRE 16 -1 (775 1300)(775 1350);
WIRE 16 -1 (775 1350)(975 1350);
WIRE 16 -1 (775 1350)(775 1400);
WIRE 16 -1 (775 1400)(975 1400);
WIRE 16 -1 (775 1400)(775 1450);
WIRE 16 -1 (775 1450)(975 1450);
WIRE 16 -1 (775 1450)(775 1500);
WIRE 16 -1 (775 1500)(775 1550);
WIRE 16 -1 (775 1500)(975 1500);
WIRE 16 -1 (775 1550)(975 1550);
WIRE 16 -1 (775 1550)(775 1600);
WIRE 16 -1 (775 1600)(975 1600);
WIRE 16 -1 (775 1600)(775 1650);
WIRE 16 -1 (775 1650)(975 1650);
WIRE 16 -1 (775 1650)(775 1700);
WIRE 16 -1 (775 1700)(975 1700);
WIRE 16 -1 (775 1700)(775 1750);
WIRE 16 -1 (775 1750)(775 1800);
WIRE 16 -1 (775 1750)(975 1750);
WIRE 16 -1 (775 1800)(975 1800);
WIRE 16 -1 (775 1800)(775 1850);
WIRE 16 -1 (775 1850)(975 1850);
WIRE 16 -1 (775 1850)(775 1900);
WIRE 16 -1 (775 1900)(975 1900);
WIRE 16 -1 (775 1900)(775 1950);
WIRE 16 -1 (775 1950)(975 1950);
WIRE 16 -1 (775 1950)(775 2000);
WIRE 16 -1 (775 2000)(775 2050);
WIRE 16 -1 (775 2000)(975 2000);
WIRE 16 -1 (775 2050)(975 2050);
WIRE 16 -1 (375 2050)(775 2050);
WIRE 16 -1 (375 2150)(375 2050);
WIRE 16 -1 (975 2150)(775 2150);
WIRE 16 -1 (775 2150)(775 2200);
WIRE 16 -1 (775 2200)(975 2200);
WIRE 16 -1 (625 2200)(775 2200);
WIRE 16 -1 (625 2300)(625 2200);
WIRE 16 -1 (775 2350)(775 2300);
WIRE 16 -1 (775 2350)(975 2350);
WIRE 16 -1 (775 2400)(775 2350);
WIRE 16 -1 (775 2300)(975 2300);
WIRE 16 -1 (975 2400)(775 2400);
WIRE 16 -1 (775 2450)(775 2400);
WIRE 16 -1 (775 2450)(975 2450);
WIRE 16 -1 (775 2500)(775 2450);
WIRE 16 -1 (775 2600)(775 2500);
WIRE 16 -1 (775 2500)(975 2500);
WIRE 16 -1 (-3125 1350)(-3025 1350);
WIRE 16 -1 (-1225 1350)(-3025 1350);
FORCEPROP 2 LAST SIG_NAME M_E_VREF
J 0
(-1975 1360);
DISPLAY 0.617021 (-1975 1360);
PAINT ORANGE (-1975 1360);
WIRE 16 -1 (-3025 1350)(-3025 1250);
WIRE 16 -1 (2475 3000)(2075 3000);
WIRE 16 -1 (-2075 1250)(-1225 1250);
FORCEPROP 2 LAST SIG_NAME TP_CH_E_DIMM_E1_RFU_2
J 0
(-2025 1260);
DISPLAY 0.617021 (-2025 1260);
PAINT ORANGE (-2025 1260);
FORCEPROP 2 LASTPROP $XRERR UNIQUE?
J 0
(-2315 1250);
DISPLAY 0.638298 (-2315 1250);
PAINT MONO (-2315 1250);
DISPLAY INVISIBLE (-2315 1250);
WIRE 16 -1 (-2075 1150)(-1225 1150);
FORCEPROP 2 LAST SIG_NAME TP_CH_E_DIMM_E1_RFU_0
J 0
(-2025 1160);
DISPLAY 0.617021 (-2025 1160);
PAINT ORANGE (-2025 1160);
FORCEPROP 2 LASTPROP $XRERR UNIQUE?
J 0
(-2315 1150);
DISPLAY 0.638298 (-2315 1150);
PAINT MONO (-2315 1150);
DISPLAY INVISIBLE (-2315 1150);
WIRE 16 -1 (-2075 1200)(-1225 1200);
FORCEPROP 2 LAST SIG_NAME TP_CH_E_DIMM_E1_RFU_1
J 0
(-2025 1210);
DISPLAY 0.617021 (-2025 1210);
PAINT ORANGE (-2025 1210);
FORCEPROP 2 LASTPROP $XRERR UNIQUE?
J 0
(-2315 1200);
DISPLAY 0.638298 (-2315 1200);
PAINT MONO (-2315 1200);
DISPLAY INVISIBLE (-2315 1200);
WIRE 16 -1 (-1225 1850)(-2250 1850);
FORCEPROP 2 LAST SIG_NAME M_E_ALERT_N
J 0
(-2200 1860);
DISPLAY 0.617021 (-2200 1860);
PAINT ORANGE (-2200 1860);
WIRE 16 -1 (-1225 1800)(-2225 1800);
FORCEPROP 2 LAST SIG_NAME M_E_ACT_N
J 0
(-2200 1810);
DISPLAY 0.617021 (-2200 1810);
PAINT ORANGE (-2200 1810);
WIRE 16 -1 (-2075 1050)(-1225 1050);
FORCEPROP 2 LAST SIG_NAME FM_ADR_COMPLETE_DEF_N
J 0
(-2025 1060);
DISPLAY 0.617021 (-2025 1060);
PAINT ORANGE (-2025 1060);
WIRE 16 -1 (-1225 1500)(-2025 1500);
WIRE 16 -1 (-2025 1450)(-1225 1450);
FORCEPROP 2 LAST SIG_NAME SMB_DDR_DEF_VPP_SCL
J 0
(-1985 1460);
DISPLAY 0.617021 (-1985 1460);
PAINT ORANGE (-1985 1460);
WIRE 16 -1 (-25 1400)(-225 1400);
WIRE 16 -1 (-25 1350)(-225 1350);
WIRE 16 -1 (-25 1450)(-225 1450);
WIRE 16 -1 (-25 1500)(-225 1500);
WIRE 16 -1 (-25 1750)(-225 1750);
WIRE 16 -1 (-25 1700)(-225 1700);
WIRE 16 -1 (-25 1650)(-225 1650);
WIRE 16 -1 (-25 1550)(-225 1550);
WIRE 16 -1 (-25 1600)(-225 1600);
WIRE 16 -1 (-25 2000)(-225 2000);
WIRE 16 -1 (-25 1950)(-225 1950);
WIRE 16 -1 (-25 1900)(-225 1900);
WIRE 16 -1 (-25 1850)(-225 1850);
WIRE 16 -1 (-25 1800)(-225 1800);
WIRE 16 -1 (-1625 1950)(-1625 2400);
WIRE 16 -1 (-1225 1950)(-1625 1950);
WIRE 16 -1 (-1625 2400)(-2225 2400);
FORCEPROP 2 LAST SIG_NAME M_DEF_RST_N
J 0
(-2200 2410);
DISPLAY 0.617021 (-2200 2410);
PAINT ORANGE (-2200 2410);
WIRE 16 -1 (-1675 1900)(-1675 2200);
WIRE 16 -1 (-1675 1900)(-1225 1900);
WIRE 16 -1 (-1675 2200)(-2400 2200);
FORCEPROP 2 LAST SIG_NAME FM_DIMM_EVENT_COD_N
J 0
(-2335 2227);
DISPLAY 0.617021 (-2335 2227);
PAINT ORANGE (-2335 2227);
WIRE 16 -1 (-1575 2000)(-1575 2450);
WIRE 16 -1 (-1225 2000)(-1575 2000);
WIRE 16 -1 (-1575 2450)(-2225 2450);
FORCEPROP 2 LAST SIG_NAME M_E_PAR
J 0
(-2200 2460);
DISPLAY 0.617021 (-2200 2460);
PAINT ORANGE (-2200 2460);
WIRE 16 -1 (-1225 2400)(-1425 2400);
WIRE 16 -1 (-1225 2350)(-1425 2350);
WIRE 16 -1 (-1225 2300)(-1425 2300);
WIRE 16 -1 (-1225 2250)(-1425 2250);
WIRE 16 -1 (-1225 2200)(-1425 2200);
WIRE 16 -1 (-1225 2150)(-1425 2150);
WIRE 16 -1 (-1225 2100)(-1425 2100);
WIRE 16 -1 (-1225 2450)(-1425 2450);
WIRE 16 -1 (-1225 2550)(-1425 2550);
WIRE 16 -1 (-1225 3000)(-1425 3000);
WIRE 16 -1 (-1225 2950)(-1425 2950);
WIRE 16 -1 (-1225 2900)(-1425 2900);
WIRE 16 -1 (-1225 2750)(-1475 2750);
WIRE 16 -1 (-1225 2600)(-1425 2600);
WIRE 16 -1 (-1225 2700)(-1475 2700);
WIRE 16 -1 (-1225 2850)(-1425 2850);
WIRE 16 -1 (-1375 3100)(-1375 3050);
WIRE 16 -1 (-1375 3100)(-2225 3100);
FORCEPROP 2 LAST SIG_NAME M_E_C<2>
J 0
(-2200 3110);
DISPLAY 0.617021 (-2200 3110);
PAINT ORANGE (-2200 3110);
WIRE 16 -1 (-1375 3050)(-1225 3050);
WIRE 16 -1 (-1225 3200)(-1825 3200);
WIRE 16 -1 (-1225 3300)(-1825 3300);
WIRE 16 -1 (-1225 3250)(-1975 3250);
WIRE 16 -1 (-1225 3150)(-1975 3150);
WIRE 16 -1 (-1225 3550)(-1425 3550);
WIRE 16 -1 (-1225 3400)(-1425 3400);
WIRE 16 -1 (-1225 3450)(-1425 3450);
WIRE 16 -1 (-1225 3500)(-1425 3500);
WIRE 16 -1 (-1225 3650)(-1425 3650);
WIRE 16 -1 (-1225 3700)(-1425 3700);
WIRE 16 -1 (-1225 3800)(-1425 3800);
WIRE 16 -1 (-1225 3850)(-1425 3850);
WIRE 16 -1 (-1225 3900)(-1425 3900);
WIRE 16 -1 (-1225 3950)(-1425 3950);
WIRE 16 -1 (-1225 4000)(-1425 4000);
WIRE 16 -1 (-1225 4050)(-1425 4050);
WIRE 16 -1 (-1225 3750)(-1425 3750);
WIRE 16 -1 (-25 2300)(-225 2300);
WIRE 16 -1 (-25 2250)(-225 2250);
WIRE 16 -1 (-25 2150)(-225 2150);
WIRE 16 -1 (-25 2050)(-225 2050);
WIRE 16 -1 (-25 2100)(-225 2100);
WIRE 16 -1 (-25 2200)(-225 2200);
WIRE 16 -1 (-25 2550)(-225 2550);
WIRE 16 -1 (-25 2500)(-225 2500);
WIRE 16 -1 (-25 2450)(-225 2450);
WIRE 16 -1 (-25 2400)(-225 2400);
WIRE 16 -1 (-25 2350)(-225 2350);
WIRE 16 -1 (-25 2800)(-225 2800);
WIRE 16 -1 (-25 2750)(-225 2750);
WIRE 16 -1 (-25 2600)(-225 2600);
WIRE 16 -1 (-25 2700)(-225 2700);
WIRE 16 -1 (-25 2650)(-225 2650);
WIRE 16 -1 (-25 3050)(-225 3050);
WIRE 16 -1 (-25 3000)(-225 3000);
WIRE 16 -1 (-25 2950)(-225 2950);
WIRE 16 -1 (-25 2900)(-225 2900);
WIRE 16 -1 (-25 2850)(-225 2850);
WIRE 16 -1 (-25 3300)(-225 3300);
WIRE 16 -1 (-25 3200)(-225 3200);
WIRE 16 -1 (-25 3100)(-225 3100);
WIRE 16 -1 (-25 3150)(-225 3150);
WIRE 16 -1 (-25 3250)(-225 3250);
WIRE 16 -1 (-25 3550)(-225 3550);
WIRE 16 -1 (-25 3500)(-225 3500);
WIRE 16 -1 (-25 3450)(-225 3450);
WIRE 16 -1 (-25 3400)(-225 3400);
WIRE 16 -1 (-25 3350)(-225 3350);
WIRE 16 -1 (-25 3650)(-225 3650);
WIRE 16 -1 (-25 3600)(-225 3600);
WIRE 16 -1 (-25 3800)(-225 3800);
WIRE 16 -1 (-25 3750)(-225 3750);
WIRE 16 -1 (-25 3700)(-225 3700);
WIRE 16 -1 (-25 4050)(-225 4050);
WIRE 16 -1 (-25 4000)(-225 4000);
WIRE 16 -1 (-25 3950)(-225 3950);
WIRE 16 -1 (-25 3900)(-225 3900);
WIRE 16 -1 (-25 3850)(-225 3850);
WIRE 16 -1 (-1225 4250)(-1425 4250);
WIRE 16 -1 (-1225 4300)(-1425 4300);
WIRE 16 -1 (-1225 4500)(-1425 4500);
WIRE 16 -1 (-1225 4100)(-1425 4100);
WIRE 16 -1 (-1225 4150)(-1425 4150);
WIRE 16 -1 (-1225 4200)(-1425 4200);
WIRE 16 -1 (-1225 4350)(-1425 4350);
WIRE 16 -1 (-1225 4400)(-1425 4400);
WIRE 16 -1 (-1225 4450)(-1425 4450);
WIRE 16 -1 (-25 4350)(-225 4350);
WIRE 16 -1 (-25 4300)(-225 4300);
WIRE 16 -1 (-25 4150)(-225 4150);
WIRE 16 -1 (-25 4100)(-225 4100);
WIRE 16 -1 (-25 4200)(-225 4200);
WIRE 16 -1 (-25 4250)(-225 4250);
WIRE 16 -1 (-25 4500)(-225 4500);
WIRE 16 -1 (-25 4450)(-225 4450);
WIRE 16 -1 (-25 4400)(-225 4400);
WIRE 16 -1 (2275 3050)(2075 3050);
WIRE 16 -1 (2275 3150)(2075 3150);
WIRE 16 -1 (2275 3250)(2075 3250);
WIRE 16 -1 (2275 3350)(2075 3350);
WIRE 16 -1 (2275 3450)(2075 3450);
WIRE 16 -1 (2275 3550)(2075 3550);
WIRE 16 -1 (2475 3100)(2075 3100);
WIRE 16 -1 (2475 3200)(2075 3200);
WIRE 16 -1 (2475 3300)(2075 3300);
WIRE 16 -1 (2475 3400)(2075 3400);
WIRE 16 -1 (2475 3500)(2075 3500);
WIRE 16 -1 (2275 3650)(2075 3650);
WIRE 16 -1 (2275 3750)(2075 3750);
WIRE 16 -1 (2275 4050)(2075 4050);
WIRE 16 -1 (2275 3850)(2075 3850);
WIRE 16 -1 (2275 3950)(2075 3950);
WIRE 16 -1 (2475 4000)(2075 4000);
WIRE 16 -1 (2475 3600)(2075 3600);
WIRE 16 -1 (2475 3700)(2075 3700);
WIRE 16 -1 (2475 3800)(2075 3800);
WIRE 16 -1 (2475 3900)(2075 3900);
WIRE 16 -1 (2275 4150)(2075 4150);
WIRE 16 -1 (2275 4250)(2075 4250);
WIRE 16 -1 (2275 4350)(2075 4350);
WIRE 16 -1 (2275 4450)(2075 4450);
WIRE 16 -1 (2275 4550)(2075 4550);
WIRE 16 -1 (2475 4100)(2075 4100);
WIRE 16 -1 (2475 4200)(2075 4200);
WIRE 16 -1 (2475 4300)(2075 4300);
WIRE 16 -1 (2475 4400)(2075 4400);
WIRE 16 -1 (2475 4500)(2075 4500);
WIRE 16 -1 (2475 4600)(2075 4600);
WIRE 16 -1 (2275 4650)(2075 4650);
WIRE 16 -1 (2275 4750)(2075 4750);
WIRE 16 -1 (2475 4700)(2075 4700);
DOT 1 (775 2400);
DOT 1 (775 2350);
DOT 1 (775 1150);
DOT 1 (-1475 1700);
DOT 1 (4125 3200);
DOT 1 (4125 3150);
DOT 1 (4125 3100);
DOT 1 (4125 3000);
DOT 1 (4125 3050);
DOT 1 (4125 2950);
DOT 1 (4125 2900);
DOT 1 (4125 2850);
DOT 1 (4125 2800);
DOT 1 (4125 2750);
DOT 1 (4125 2700);
DOT 1 (4125 2650);
DOT 1 (4125 2600);
DOT 1 (4125 2550);
DOT 1 (4125 2500);
DOT 1 (4125 2450);
DOT 1 (4125 2400);
DOT 1 (4125 2350);
DOT 1 (4125 2300);
DOT 1 (4125 2250);
DOT 1 (4125 2200);
DOT 1 (4125 2150);
DOT 1 (4125 2100);
DOT 1 (4125 2050);
DOT 1 (4125 2000);
DOT 1 (4125 1950);
DOT 1 (4125 1850);
DOT 1 (4125 1900);
DOT 1 (4125 1800);
DOT 1 (4125 1750);
DOT 1 (4125 1700);
DOT 1 (4125 1650);
DOT 1 (4125 1600);
DOT 1 (4125 1550);
DOT 1 (4125 1500);
DOT 1 (4125 1450);
DOT 1 (4125 1400);
DOT 1 (4125 1350);
DOT 1 (4125 1300);
DOT 1 (4125 1150);
DOT 1 (4125 1200);
DOT 1 (4125 1250);
DOT 1 (4125 1050);
DOT 1 (4125 1100);
DOT 1 (4125 1000);
DOT 1 (4125 950);
DOT 1 (2725 3200);
DOT 1 (2725 3150);
DOT 1 (2725 3100);
DOT 1 (2725 2950);
DOT 1 (2725 3000);
DOT 1 (2725 3050);
DOT 1 (2725 2900);
DOT 1 (2725 2850);
DOT 1 (2725 2800);
DOT 1 (2725 2750);
DOT 1 (2725 2700);
DOT 1 (2725 2600);
DOT 1 (2725 2650);
DOT 1 (2725 2550);
DOT 1 (2725 2500);
DOT 1 (2725 2450);
DOT 1 (2725 2350);
DOT 1 (2725 2400);
DOT 1 (2725 2300);
DOT 1 (2725 2250);
DOT 1 (2725 2200);
DOT 1 (2725 2050);
DOT 1 (2725 2100);
DOT 1 (2725 2150);
DOT 1 (2725 2000);
DOT 1 (2725 1950);
DOT 1 (2725 1800);
DOT 1 (2725 1850);
DOT 1 (2725 1900);
DOT 1 (2725 1700);
DOT 1 (2725 1750);
DOT 1 (2175 2500);
DOT 1 (2725 1650);
DOT 1 (2725 1600);
DOT 1 (2725 1550);
DOT 1 (2725 1450);
DOT 1 (2725 1500);
DOT 1 (2725 1400);
DOT 1 (2725 1350);
DOT 1 (2725 1300);
DOT 1 (2725 1200);
DOT 1 (2725 1150);
DOT 1 (2725 1250);
DOT 1 (2725 1100);
DOT 1 (2725 1050);
DOT 1 (2725 1000);
DOT 1 (2725 950);
DOT 1 (775 2450);
DOT 1 (775 2500);
DOT 1 (775 2200);
DOT 1 (775 2050);
DOT 1 (775 2000);
DOT 1 (775 1950);
DOT 1 (775 1900);
DOT 1 (775 1850);
DOT 1 (775 1800);
DOT 1 (775 1750);
DOT 1 (775 1700);
DOT 1 (775 1650);
DOT 1 (775 1550);
DOT 1 (775 1600);
DOT 1 (775 1500);
DOT 1 (775 1450);
DOT 1 (775 1300);
DOT 1 (775 1350);
DOT 1 (775 1250);
DOT 1 (775 1200);
DOT 1 (775 1100);
DOT 1 (775 1050);
DOT 1 (775 1000);
DOT 1 (775 950);
DOT 1 (775 900);
DOT 1 (775 850);
DOT 1 (-3025 1350);
DOT 1 (775 1400);
DOT 1 (-1475 1600);
FORCENOTE
PLACE CAP NEAR DIMM CONNECTOR
(-3688 802) 0;
DISPLAY LEFT (-3688 802);
DISPLAY 1.276596 (-3688 802);
PAINT PURPLE (-3688 802);
FORCENOTE
SMBUS ADDR: 0XA6
(-3625 659) 0;
DISPLAY LEFT (-3625 659);
DISPLAY 1.957447 (-3625 659);
PAINT PURPLE (-3625 659);
QUIT
